G04 ================== begin FILE IDENTIFICATION RECORD ==================*
G04 Layout Name:  12004-1.brd*
G04 Film Name:    L7GND*
G04 File Format:  Gerber RS274X*
G04 File Origin:  Cadence Allegro 16.2-S033*
G04 Origin Date:  Tue Oct 16 14:36:10 2012*
G04 *
G04 Layer:  VIA CLASS/L7GND*
G04 Layer:  PIN/L7GND*
G04 Layer:  ETCH/L7GND*
G04 Layer:  DRAWING FORMAT/LAYER_PCB_STORY*
G04 Layer:  DRAWING FORMAT/LAYER_L7GND*
G04 *
G04 Offset:    (0.00 0.00)*
G04 Mirror:    No*
G04 Mode:      Negative*
G04 Rotation:  0*
G04 FullContactRelief:  No*
G04 UndefLineWidth:     6.00*
G04 ================== end FILE IDENTIFICATION RECORD ====================*
%FSLAX35Y35*MOIN*%
%IR0*IPPOS*OFA0.00000B0.00000*MIA0B0*SFA1.00000B1.00000*%
%ADD15C,.03*%
%ADD14C,.032*%
%ADD22C,.09*%
%ADD19C,.036*%
%ADD17C,.063*%
%ADD26C,.073*%
%ADD24C,.089*%
%AMMACRO16*
4,1,13,.02327,.00913,
.024502,.004951,
.024989,.000621,
.024717,-.003728,
.023695,-.007964,
.02327,-.00913,
.02707,-.01293,
.028904,-.008033,
.02986,-.002892,
.029908,.002337,
.029048,.007495,
.027305,.012426,
.02707,.01293,
.02327,.00913,
270.*
4,1,13,.00913,-.02327,
.004951,-.024502,
.000621,-.024989,
-.003728,-.024717,
-.007964,-.023695,
-.00913,-.02327,
-.01293,-.02707,
-.008033,-.028904,
-.002892,-.02986,
.002337,-.029908,
.007495,-.029048,
.012426,-.027305,
.01293,-.02707,
.00913,-.02327,
270.*
4,1,13,-.02327,-.00913,
-.024502,-.004951,
-.024989,-.000621,
-.024717,.003728,
-.023695,.007964,
-.02327,.00913,
-.02707,.01293,
-.028904,.008033,
-.02986,.002892,
-.029908,-.002337,
-.029048,-.007495,
-.027305,-.012426,
-.02707,-.01293,
-.02327,-.00913,
270.*
4,1,13,-.00913,.02327,
-.004951,.024502,
-.000621,.024989,
.003728,.024717,
.007964,.023695,
.00913,.02327,
.01293,.02707,
.008033,.028904,
.002892,.02986,
-.002337,.029908,
-.007495,.029048,
-.012426,.027305,
-.01293,.02707,
-.00913,.02327,
270.*
%
%ADD16MACRO16*%
%AMMACRO27*
4,1,15,.00398,.00044,
.003999,.000208,
.004004,-.000025,
.003996,-.000258,
.00398,-.00044,
.00483,-.00129,
.004897,-.001007,
.004947,-.000721,
.004981,-.000432,
.004997,-.000141,
.004997,.000149,
.00498,.00044,
.004946,.000729,
.004895,.001015,
.00483,.00129,
.00398,.00044,
90.*
4,1,15,.00044,-.00398,
.000208,-.003999,
-.000025,-.004004,
-.000258,-.003996,
-.00044,-.00398,
-.00129,-.00483,
-.001007,-.004897,
-.000721,-.004947,
-.000432,-.004981,
-.000141,-.004997,
.000149,-.004997,
.00044,-.00498,
.000729,-.004946,
.001015,-.004895,
.00129,-.00483,
.00044,-.00398,
90.*
4,1,15,-.00398,-.00044,
-.003999,-.000208,
-.004004,.000025,
-.003996,.000258,
-.00398,.00044,
-.00483,.00129,
-.004897,.001007,
-.004947,.000721,
-.004981,.000432,
-.004997,.000141,
-.004997,-.000149,
-.00498,-.00044,
-.004946,-.000729,
-.004895,-.001015,
-.00483,-.00129,
-.00398,-.00044,
90.*
4,1,15,-.00044,.00398,
-.000208,.003999,
.000025,.004004,
.000258,.003996,
.00044,.00398,
.00129,.00483,
.001007,.004897,
.000721,.004947,
.000432,.004981,
.000141,.004997,
-.000149,.004997,
-.00044,.00498,
-.000729,.004946,
-.001015,.004895,
-.00129,.00483,
-.00044,.00398,
90.*
%
%ADD27MACRO27*%
%AMMACRO11*
4,1,15,.00398,.00044,
.003999,.000208,
.004004,-.000025,
.003996,-.000258,
.00398,-.00044,
.00483,-.00129,
.004897,-.001007,
.004947,-.000721,
.004981,-.000432,
.004997,-.000141,
.004997,.000149,
.00498,.00044,
.004946,.000729,
.004895,.001015,
.00483,.00129,
.00398,.00044,
0.0*
4,1,15,.00044,-.00398,
.000208,-.003999,
-.000025,-.004004,
-.000258,-.003996,
-.00044,-.00398,
-.00129,-.00483,
-.001007,-.004897,
-.000721,-.004947,
-.000432,-.004981,
-.000141,-.004997,
.000149,-.004997,
.00044,-.00498,
.000729,-.004946,
.001015,-.004895,
.00129,-.00483,
.00044,-.00398,
0.0*
4,1,15,-.00398,-.00044,
-.003999,-.000208,
-.004004,.000025,
-.003996,.000258,
-.00398,.00044,
-.00483,.00129,
-.004897,.001007,
-.004947,.000721,
-.004981,.000432,
-.004997,.000141,
-.004997,-.000149,
-.00498,-.00044,
-.004946,-.000729,
-.004895,-.001015,
-.00483,-.00129,
-.00398,-.00044,
0.0*
4,1,15,-.00044,.00398,
-.000208,.003999,
.000025,.004004,
.000258,.003996,
.00044,.00398,
.00129,.00483,
.001007,.004897,
.000721,.004947,
.000432,.004981,
.000141,.004997,
-.000149,.004997,
-.00044,.00498,
-.000729,.004946,
-.001015,.004895,
-.00129,.00483,
-.00044,.00398,
0.0*
%
%ADD11MACRO11*%
%AMMACRO18*
4,1,17,.09314,.06486,
.102988,.047701,
.109706,.029093,
.113092,.0096,
.113041,-.010184,
.109555,-.029658,
.10274,-.048232,
.09314,-.06486,
.09673,-.06845,
.107147,-.050613,
.114308,-.031238,
.117996,-.010914,
.118098,.009741,
.114613,.030101,
.107644,.049546,
.097406,.067485,
.09673,.06845,
.09314,.06486,
270.*
4,1,17,.06486,-.09314,
.047701,-.102988,
.029093,-.109706,
.0096,-.113092,
-.010184,-.113041,
-.029658,-.109555,
-.048232,-.10274,
-.06486,-.09314,
-.06845,-.09673,
-.050613,-.107147,
-.031238,-.114308,
-.010914,-.117996,
.009741,-.118098,
.030101,-.114613,
.049546,-.107644,
.067485,-.097406,
.06845,-.09673,
.06486,-.09314,
270.*
4,1,17,-.09314,-.06486,
-.102988,-.047701,
-.109706,-.029093,
-.113092,-.0096,
-.113041,.010184,
-.109555,.029658,
-.10274,.048232,
-.09314,.06486,
-.09673,.06845,
-.107147,.050613,
-.114308,.031238,
-.117996,.010914,
-.118098,-.009741,
-.114613,-.030101,
-.107644,-.049546,
-.097406,-.067485,
-.09673,-.06845,
-.09314,-.06486,
270.*
4,1,17,-.06486,.09314,
-.047701,.102988,
-.029093,.109706,
-.0096,.113092,
.010184,.113041,
.029658,.109555,
.048232,.10274,
.06486,.09314,
.06845,.09673,
.050613,.107147,
.031238,.114308,
.010914,.117996,
-.009741,.118098,
-.030101,.114613,
-.049546,.107644,
-.067485,.097406,
-.06845,.09673,
-.06486,.09314,
270.*
%
%ADD18MACRO18*%
%AMMACRO21*
4,1,13,.02594,.0118,
.027595,.007116,
.028411,.002216,
.028365,-.002751,
.027456,-.007635,
.02594,-.0118,
.02968,-.01554,
.031928,-.01015,
.033205,-.004452,
.033474,.001382,
.032725,.007174,
.030982,.012747,
.02968,.01554,
.02594,.0118,
270.*
4,1,13,.0118,-.02594,
.007116,-.027595,
.002216,-.028411,
-.002751,-.028365,
-.007635,-.027456,
-.0118,-.02594,
-.01554,-.02968,
-.01015,-.031928,
-.004452,-.033205,
.001382,-.033474,
.007174,-.032725,
.012747,-.030982,
.01554,-.02968,
.0118,-.02594,
270.*
4,1,13,-.02594,-.0118,
-.027595,-.007116,
-.028411,-.002216,
-.028365,.002751,
-.027456,.007635,
-.02594,.0118,
-.02968,.01554,
-.031928,.01015,
-.033205,.004452,
-.033474,-.001382,
-.032725,-.007174,
-.030982,-.012747,
-.02968,-.01554,
-.02594,-.0118,
270.*
4,1,13,-.0118,.02594,
-.007116,.027595,
-.002216,.028411,
.002751,.028365,
.007635,.027456,
.0118,.02594,
.01554,.02968,
.01015,.031928,
.004452,.033205,
-.001382,.033474,
-.007174,.032725,
-.012747,.030982,
-.01554,.02968,
-.0118,.02594,
270.*
%
%ADD21MACRO21*%
%ADD13C,.107*%
%ADD28C,.225*%
%ADD12C,.186*%
%ADD10C,.168*%
%AMMACRO20*
4,1,13,.02442,.01028,
.025834,.005883,
.026463,.001308,
.026288,-.003307,
.025315,-.007822,
.02442,-.01028,
.02819,-.01405,
.030201,-.008941,
.031295,-.003561,
.031438,.001927,
.030626,.007357,
.028883,.012564,
.02819,.01405,
.02442,.01028,
90.*
4,1,13,.01028,-.02442,
.005883,-.025834,
.001308,-.026463,
-.003307,-.026288,
-.007822,-.025315,
-.01028,-.02442,
-.01405,-.02819,
-.008941,-.030201,
-.003561,-.031295,
.001927,-.031438,
.007357,-.030626,
.012564,-.028883,
.01405,-.02819,
.01028,-.02442,
90.*
4,1,13,-.02442,-.01028,
-.025834,-.005883,
-.026463,-.001308,
-.026288,.003307,
-.025315,.007822,
-.02442,.01028,
-.02819,.01405,
-.030201,.008941,
-.031295,.003561,
-.031438,-.001927,
-.030626,-.007357,
-.028883,-.012564,
-.02819,-.01405,
-.02442,-.01028,
90.*
4,1,13,-.01028,.02442,
-.005883,.025834,
-.001308,.026463,
.003307,.026288,
.007822,.025315,
.01028,.02442,
.01405,.02819,
.008941,.030201,
.003561,.031295,
-.001927,.031438,
-.007357,.030626,
-.012564,.028883,
-.01405,.02819,
-.01028,.02442,
90.*
%
%ADD20MACRO20*%
%AMMACRO25*
4,1,14,.02819,.01405,
.030201,.008941,
.031295,.003561,
.031438,-.001927,
.030626,-.007357,
.028883,-.012564,
.02819,-.01405,
.03189,-.01775,
.034488,-.011943,
.036038,-.005773,
.036493,.000573,
.035839,.006901,
.034096,.01302,
.03189,.01775,
.02819,.01405,
0.0*
4,1,14,.01405,-.02819,
.008941,-.030201,
.003561,-.031295,
-.001927,-.031438,
-.007357,-.030626,
-.012564,-.028883,
-.01405,-.02819,
-.01775,-.03189,
-.011943,-.034488,
-.005773,-.036038,
.000573,-.036493,
.006901,-.035839,
.01302,-.034096,
.01775,-.03189,
.01405,-.02819,
0.0*
4,1,14,-.02819,-.01405,
-.030201,-.008941,
-.031295,-.003561,
-.031438,.001927,
-.030626,.007357,
-.028883,.012564,
-.02819,.01405,
-.03189,.01775,
-.034488,.011943,
-.036038,.005773,
-.036493,-.000573,
-.035839,-.006901,
-.034096,-.01302,
-.03189,-.01775,
-.02819,-.01405,
0.0*
4,1,14,-.01405,.02819,
-.008941,.030201,
-.003561,.031295,
.001927,.031438,
.007357,.030626,
.012564,.028883,
.01405,.02819,
.01775,.03189,
.011943,.034488,
.005773,.036038,
-.000573,.036493,
-.006901,.035839,
-.01302,.034096,
-.01775,.03189,
-.01405,.02819,
0.0*
%
%ADD25MACRO25*%
%AMMACRO23*
4,1,14,.0575,.02922,
.0617,.018791,
.064026,.007792,
.064406,-.003445,
.06283,-.014576,
.059344,-.025265,
.0575,-.02922,
.06121,-.03292,
.065997,-.021791,
.068778,-.01,
.069469,.002095,
.06805,.014127,
.064563,.025729,
.06121,.03292,
.0575,.02922,
0.0*
4,1,14,.02922,-.0575,
.018791,-.0617,
.007792,-.064026,
-.003445,-.064406,
-.014576,-.06283,
-.025265,-.059344,
-.02922,-.0575,
-.03292,-.06121,
-.021791,-.065997,
-.01,-.068778,
.002095,-.069469,
.014127,-.06805,
.025729,-.064563,
.03292,-.06121,
.02922,-.0575,
0.0*
4,1,14,-.0575,-.02922,
-.0617,-.018791,
-.064026,-.007792,
-.064406,.003445,
-.06283,.014576,
-.059344,.025265,
-.0575,.02922,
-.06121,.03292,
-.065997,.021791,
-.068778,.01,
-.069469,-.002095,
-.06805,-.014127,
-.064563,-.025729,
-.06121,-.03292,
-.0575,-.02922,
0.0*
4,1,14,-.02922,.0575,
-.018791,.0617,
-.007792,.064026,
.003445,.064406,
.014576,.06283,
.025265,.059344,
.02922,.0575,
.03292,.06121,
.021791,.065997,
.01,.068778,
-.002095,.069469,
-.014127,.06805,
-.025729,.064563,
-.03292,.06121,
-.02922,.0575,
0.0*
%
%ADD23MACRO23*%
%ADD29C,.02*%
%ADD30C,.006*%
%ADD36R,.06279X.02799*%
%ADD34C,.08506*%
%ADD33C,.08606*%
%ADD35R,.038X.012*%
%ADD32C,.10306*%
%ADD31C,.18206*%
G75*
%LPD*%
G75*
G36*
G01X-149740Y-6000D02*
X795764D01*
Y931197D01*
X-149740D01*
Y-6000D01*
G37*
%LPC*%
G75*
G36*
G01X3000Y209904D02*
X2866Y210037D01*
X2854Y210095D01*
G03X-2503Y215452I-6791J-1434D01*
G01X-2561Y215464D01*
X-2694Y215598D01*
X-3704D01*
G03X-3937Y215602I-236J-6937D01*
G01X-139803D01*
G02X-140736Y216535I0J933D01*
G01Y338583D01*
G02X-139803Y339516I933J0D01*
G01X-62992D01*
G03X-62759Y339520I-3J6941D01*
G01X-61749D01*
X-61616Y339654D01*
X-61558Y339666D01*
G03X-56201Y345023I-1434J6791D01*
G01X-56189Y345081D01*
X-56055Y345214D01*
Y346224D01*
G03X-56051Y346457I-6937J236D01*
G01Y503937D01*
G02X-55118Y504870I933J0D01*
G01X-3937D01*
G03X-3704Y504874I-3J6941D01*
G01X-2694D01*
X-2560Y505008D01*
X-2502Y505020D01*
G03X2854Y510376I-1435J6791D01*
G01X2866Y510434D01*
X3000Y510568D01*
Y511578D01*
G03X3004Y511811I-6937J236D01*
G01Y783465D01*
G02X3937Y784398I933J0D01*
G01X74803D01*
G03X75036Y784402I-3J6941D01*
G01X76046D01*
X76179Y784536D01*
X76237Y784548D01*
G03X81594Y789905I-1434J6791D01*
G01X81606Y789963D01*
X81740Y790096D01*
Y791106D01*
G03X81744Y791339I-6937J236D01*
G01Y921260D01*
G02X82677Y922193I933J0D01*
G01X755906D01*
G02X756839Y921260I0J-933D01*
G01Y821457D01*
G03X763780Y814516I6941J0D01*
G01X767612D01*
X767616Y814520D01*
X773015D01*
Y792173D01*
X771286D01*
X771282Y792177D01*
X765945D01*
G03Y778689I0J-6744D01*
G01X772462D01*
X772466Y778693D01*
X773015D01*
Y740602D01*
X763780D01*
G03X756839Y733661I0J-6941D01*
G01Y663976D01*
G03X763780Y657035I6941J0D01*
G01X765572D01*
X765576Y657039D01*
X773015D01*
Y382724D01*
X770786D01*
X770782Y382728D01*
X765945D01*
G03Y369240I0J-6744D01*
G01X770062D01*
X770066Y369244D01*
X773015D01*
Y331150D01*
X767436D01*
X767432Y331154D01*
X763780D01*
G03X763547Y331150I3J-6941D01*
G01X762537D01*
X762404Y331016D01*
X762346Y331004D01*
G03X756989Y325647I1434J-6791D01*
G01X756977Y325589D01*
X756843Y325456D01*
Y324446D01*
G03X756839Y324213I6937J-236D01*
G01Y3937D01*
G02X755906Y3004I-933J0D01*
G01X3937D01*
G02X3004Y3937I0J933D01*
G01Y208661D01*
G03X3000Y208894I-6941J-3D01*
G01Y209904D01*
G37*
%LPD*%
G75*
G36*
G01X708866Y31408D02*
X708859Y31414D01*
X708852Y31421D01*
G02X708179Y32132I7684J7948D01*
G01X708148Y32166D01*
X708120Y32201D01*
G02X706495Y34742I8414J7171D01*
G01X706486Y34761D01*
X706480Y34776D01*
G02X705946Y36193I10054J4598D01*
G01X705945Y36197D01*
X705944Y36202D01*
G02X705542Y38197I10590J3172D01*
G01X705541Y38207D01*
X705540Y38220D01*
G02X706596Y44211I10995J1151D01*
G01X706602Y44223D01*
G02X708278Y46721I9933J-4853D01*
G01X708318Y46768D01*
X708364Y46816D01*
G02X710669Y48740I8171J-7446D01*
G01X710671Y48742D01*
G02X712010Y49457I5865J-9372D01*
G01X712040Y49471D01*
X712070Y49483D01*
G02X712988Y49841I4472J-10110D01*
G01X712996Y49843D01*
G02X720074I3539J-10473D01*
G01X720082Y49841D01*
G02X721000Y49483I-3554J-10468D01*
G01X721030Y49471D01*
X721060Y49457D01*
G02X722399Y48742I-4526J-10087D01*
G01X722401Y48740D01*
G02X724706Y46816I-5866J-9370D01*
G01X724752Y46768D01*
X724792Y46721D01*
G02X726468Y44223I-8257J-7351D01*
G01X726474Y44211D01*
G02X727530Y38220I-9939J-4840D01*
G01X727529Y38207D01*
X727528Y38197D01*
G02X727126Y36202I-10992J1177D01*
G01X727125Y36197D01*
X727124Y36193D01*
G02X726590Y34776I-10588J3181D01*
G01X726584Y34761D01*
X726575Y34742D01*
G02X724950Y32201I-10039J4630D01*
G01X724922Y32166D01*
X724891Y32132D01*
G02X724218Y31421I-8357J7237D01*
G01X724211Y31414D01*
X724204Y31408D01*
G02X708866I-7669J7962D01*
G37*
G54D36*
X63982Y563482D03*
X63970Y567510D03*
X63945Y572988D03*
X63848Y576808D03*
X63898Y596340D03*
X63878Y600220D03*
X63768Y606022D03*
X63793Y609906D03*
X64408Y680774D03*
X64446Y684704D03*
X64505Y690520D03*
X64384Y694390D03*
X63545Y714666D03*
X63520Y718554D03*
X63398Y724584D03*
X63447Y728478D03*
X153930Y814144D03*
X154004Y817819D03*
X152492Y828987D03*
X152516Y832735D03*
X152466Y837116D03*
X152320Y840888D03*
X153294Y850186D03*
X153222Y853740D03*
G54D34*
X144843Y812994D03*
Y860234D03*
G54D33*
X54724Y557087D03*
Y620079D03*
Y675197D03*
Y738189D03*
X144843Y798779D03*
Y874449D03*
G54D35*
X687858Y456177D03*
X701858D03*
X687858Y458146D03*
X701858D03*
X687858Y460114D03*
X701858D03*
X687858Y462083D03*
X701858D03*
X687858Y467989D03*
X701858D03*
X687858Y469957D03*
X701858D03*
X687858Y471926D03*
X701858D03*
X687858Y473894D03*
X701858D03*
G54D32*
X-33503Y269685D03*
G54D31*
X-59094Y277559D03*
X-7913D03*
G54D15*
X8789Y376072D03*
X6944Y414616D03*
X6855Y436844D03*
X6750Y425868D03*
X7180Y449205D03*
X62439Y413744D03*
X66931Y398350D03*
X74863Y390483D03*
X64055Y389700D03*
X33722Y401639D03*
X74544Y414071D03*
X70779Y402387D03*
X79016Y410283D03*
X35738Y406956D03*
X14422Y411528D03*
X14657Y416838D03*
X10615Y411073D03*
X26551Y394546D03*
X30232Y416556D03*
X23922Y415548D03*
X35994Y410146D03*
X43719Y414419D03*
X32141Y407501D03*
X31808Y410684D03*
X18448Y402542D03*
X74817Y409752D03*
X26972Y399588D03*
X70882Y409794D03*
X66938Y410045D03*
X78939Y414083D03*
X18448Y406788D03*
X53976Y389814D03*
X74894Y398251D03*
X62031Y399713D03*
X74702Y394300D03*
X74869Y406315D03*
X78300Y386505D03*
X64948Y386626D03*
X78362Y398337D03*
X77963Y381183D03*
X70888Y394222D03*
X66963Y473083D03*
X66931Y484968D03*
X79081Y465348D03*
X70704Y429620D03*
X67015Y449433D03*
X74639Y441855D03*
X78754Y453353D03*
X78811Y426113D03*
X52151Y456887D03*
X66903Y457689D03*
X78798Y433983D03*
X17072Y435057D03*
X74836Y453477D03*
X59980Y482517D03*
X78754Y449904D03*
X67112Y481066D03*
X70488Y465291D03*
X74450Y457429D03*
X70713Y461504D03*
X36237Y441728D03*
X70908Y457771D03*
X70898Y418271D03*
X61038Y424878D03*
X74726Y425594D03*
X59209Y438908D03*
X46853Y441796D03*
X78561Y421756D03*
X70809Y438057D03*
X43659Y432766D03*
X43088Y438073D03*
X45486Y456341D03*
X38566Y451290D03*
X42312Y463368D03*
X74780Y429794D03*
X24357Y423051D03*
X37988Y438328D03*
X19757Y418538D03*
X29472Y428016D03*
X78738Y429679D03*
X11964Y421332D03*
X52476Y439395D03*
X13062Y429279D03*
X74656Y421838D03*
X17936Y431103D03*
X14206Y433632D03*
X15424Y422722D03*
X70857Y433857D03*
X19015Y426461D03*
X14147Y438989D03*
X74752Y437655D03*
X74437Y473159D03*
X15872Y441916D03*
X74460Y461287D03*
X78793Y445704D03*
X70868Y477094D03*
X23748Y436249D03*
X26611Y441743D03*
X70909Y469595D03*
X30513Y437850D03*
X74702Y469183D03*
X37420Y461517D03*
X31517Y445328D03*
X70868Y473157D03*
X28472Y447107D03*
X48298Y454813D03*
X70602Y453533D03*
X74805Y477094D03*
X70868Y481031D03*
X74598Y485021D03*
X78421Y473078D03*
X74695Y449260D03*
X59063Y485583D03*
X79134Y461339D03*
X74870Y488789D03*
X69523Y567387D03*
X69555Y564187D03*
X69599Y601527D03*
X69569Y598159D03*
X69388Y576660D03*
X69450Y573460D03*
X69569Y608021D03*
X69496Y611417D03*
X69661Y591387D03*
X66579Y592250D03*
X63125Y592801D03*
X62681Y589462D03*
X69451Y684303D03*
Y681103D03*
Y691003D03*
X69474Y694403D03*
X69523Y718313D03*
Y715113D03*
X69472Y729385D03*
X69548Y726185D03*
X145771Y414191D03*
X82555Y406288D03*
X110472Y394496D03*
X145765Y406438D03*
X122053Y406224D03*
X114175Y410161D03*
X125990Y394413D03*
X141738D03*
X98427Y414098D03*
X125990D03*
X90553Y410161D03*
X102263Y414083D03*
X141887Y410202D03*
X102364Y406224D03*
X133864Y410161D03*
X94367Y394479D03*
X102364Y402287D03*
X106301Y398350D03*
Y402287D03*
X102364Y398350D03*
X110238Y402287D03*
X114175D03*
X110238Y398350D03*
X114175D03*
X85721Y385798D03*
X149362Y413951D03*
X149498Y406396D03*
X114175Y406224D03*
X126063Y406183D03*
X141738Y406224D03*
X106301D03*
X149663Y410083D03*
X82459Y413976D03*
X90566Y394383D03*
X82663Y402406D03*
X133864Y402287D03*
X86772Y414047D03*
X122053Y402287D03*
X133864Y398350D03*
X137801D03*
X122053D03*
X137801Y402287D03*
X125990D03*
Y398350D03*
X129927Y402287D03*
Y398350D03*
X82663Y398383D03*
X141738Y402287D03*
Y398350D03*
X145865Y402287D03*
Y398350D03*
X149488Y402114D03*
X149583Y398383D03*
X90359Y469275D03*
X137801Y453472D03*
Y445598D03*
X133864Y437720D03*
Y445598D03*
X133953Y425813D03*
X102684Y445671D03*
X106263Y437583D03*
X133864Y433783D03*
X102364Y429846D03*
X98363Y421883D03*
X94263Y418129D03*
X106210Y421976D03*
X110332Y425814D03*
X149612Y445598D03*
Y433783D03*
X86493Y441401D03*
X86616Y433783D03*
X86687Y421669D03*
X137801Y477094D03*
X149612D03*
X114175D03*
X102364D03*
X98626Y477049D03*
X130081Y425912D03*
X121943Y425834D03*
X114091Y425962D03*
X122053Y421972D03*
Y418035D03*
X106301D03*
X114175D03*
X133863Y417883D03*
X117951Y437592D03*
X114175Y445598D03*
X110263Y441683D03*
X118189Y445711D03*
X125990Y445598D03*
X110238Y437720D03*
X125990D03*
X110222Y417989D03*
X106341Y426062D03*
X82564Y449659D03*
X145663Y441483D03*
X98288Y441609D03*
X149612Y429846D03*
X110238Y453472D03*
X122053Y429846D03*
X114063Y429879D03*
X125897Y453240D03*
X118238Y453417D03*
X149594Y480923D03*
X94518Y449186D03*
X86768Y449383D03*
X98427Y484968D03*
Y481031D03*
X102364D03*
Y484968D03*
X106301D03*
Y481031D03*
X114175Y484968D03*
Y481031D03*
X122053Y484968D03*
Y481031D03*
X125990Y484968D03*
Y481031D03*
X145567Y453547D03*
X145763Y449583D03*
X149576Y465497D03*
X98597Y457291D03*
X94490Y429846D03*
X90463Y425983D03*
X90480Y437608D03*
X82562Y425980D03*
X86505Y425987D03*
X90380Y429650D03*
X130080Y457372D03*
X94490Y437720D03*
X82681Y430041D03*
X141827Y461346D03*
X98334Y429754D03*
X98427Y437720D03*
X94369Y425977D03*
X82677Y433595D03*
X149563Y469220D03*
X94490Y433783D03*
X141738Y481031D03*
X82663Y457486D03*
X141738Y484968D03*
X98433Y449125D03*
X137801Y481031D03*
X102600Y425983D03*
X137801Y484968D03*
X94554Y421911D03*
X133864Y481031D03*
X149612Y437720D03*
X94414Y445605D03*
X133864Y484968D03*
X86663Y429536D03*
X82542Y445403D03*
X98427Y433783D03*
X86568Y445669D03*
X90426Y449431D03*
X90563Y417983D03*
X145675Y425909D03*
X82573Y441360D03*
X145675Y437720D03*
X98280Y445405D03*
X90426Y441880D03*
X145675Y481031D03*
Y484968D03*
X145737Y418077D03*
X141738Y429846D03*
X86663Y453583D03*
X82732Y453139D03*
X102227Y473344D03*
X145675Y469220D03*
X90376Y476918D03*
X110238Y477094D03*
X141738D03*
X137801Y473157D03*
X98427Y469046D03*
X106301Y469220D03*
X114175D03*
X126057Y469287D03*
X129927Y469220D03*
X137801D03*
X122053Y465283D03*
X133864D03*
X106301Y461346D03*
X122113Y457535D03*
X129963Y461283D03*
X110263Y457283D03*
X122158Y453388D03*
X125990Y477094D03*
X137801Y449535D03*
X149612Y425909D03*
X82535Y461227D03*
X83021Y473118D03*
X141595Y421932D03*
X141775Y426153D03*
X86735Y461382D03*
X141763Y437883D03*
X86937Y477160D03*
X141682Y417902D03*
X82759Y469436D03*
X145663Y445583D03*
X145675Y429846D03*
X142008Y457429D03*
X141863Y445583D03*
X86959Y469276D03*
X137570Y421843D03*
X145561Y421879D03*
X90965Y465270D03*
X129927Y481031D03*
Y484968D03*
X110238Y481031D03*
Y484968D03*
X94490Y481031D03*
X86663Y457283D03*
X94490Y484968D03*
X86765Y465205D03*
X138061Y418151D03*
X145675Y433783D03*
X82763Y417750D03*
X86523Y417943D03*
X94844Y469182D03*
X102469Y469134D03*
X106149Y457371D03*
X141649Y453189D03*
X149620Y485149D03*
X98682Y461441D03*
X94092Y492819D03*
X118004Y488825D03*
X133864Y488905D03*
X149612D03*
X102308Y488978D03*
X86616Y488905D03*
X91198Y595087D03*
X91123Y591887D03*
X91223Y588487D03*
X159768Y238444D03*
X160004Y233894D03*
X181576Y407810D03*
X175463Y413760D03*
X161499Y402554D03*
X169297Y402536D03*
X157502Y390427D03*
X173425Y390228D03*
X214660Y362600D03*
X176751Y387090D03*
X157251Y414149D03*
X161477Y394511D03*
X180991Y398678D03*
X180809Y414170D03*
X179225Y403667D03*
X153587Y406496D03*
X157554Y402251D03*
X157698Y406313D03*
X161475Y410299D03*
X165266Y409882D03*
X165337Y414489D03*
X153528Y410052D03*
X165455Y398256D03*
X165229Y402019D03*
X157411Y398513D03*
X169113Y398299D03*
X178031Y390023D03*
X177588Y482616D03*
X161423Y469220D03*
X153583Y461058D03*
X169297Y477094D03*
Y465283D03*
X157486Y437720D03*
Y429846D03*
X153416Y445539D03*
X169290Y417960D03*
X169297Y437720D03*
X169112Y453260D03*
X169166Y429679D03*
X153549Y429846D03*
X165621Y418066D03*
X153549Y425909D03*
X161746Y421972D03*
X177182Y467018D03*
X175477Y472360D03*
X176815Y479061D03*
X161473Y457213D03*
X165360Y477094D03*
X153549Y437720D03*
X157560Y445484D03*
X153549Y449535D03*
X174859Y469220D03*
X157322Y453385D03*
X165317Y461561D03*
X165360Y473157D03*
X161455Y453385D03*
X177763Y486293D03*
X153463Y453383D03*
X157411Y469344D03*
X161423Y477094D03*
X157486Y461346D03*
X153690Y469111D03*
X165411Y429590D03*
X175161Y434723D03*
X161423Y445598D03*
X153549Y421972D03*
X161423Y449430D03*
X153549Y473157D03*
X161670Y418161D03*
X176662Y418122D03*
X153201Y418097D03*
X157401Y418143D03*
X157463Y421883D03*
X157486Y425909D03*
X173458Y457178D03*
X178053Y474260D03*
X174601Y481467D03*
X165319Y453134D03*
X165353Y480812D03*
X157486Y433783D03*
X165360Y421972D03*
X153646Y457393D03*
X161294Y461561D03*
X165363Y425783D03*
X157393Y457572D03*
X165217Y457361D03*
X165355Y433382D03*
X161423Y473157D03*
X165355Y437582D03*
X165360Y445598D03*
X157411Y449556D03*
X169157Y445598D03*
X157508Y480990D03*
X165288Y449306D03*
X157486Y484968D03*
X153601Y480894D03*
X153586Y485118D03*
X161423Y433783D03*
X181414Y490281D03*
X174475Y488016D03*
X178084Y493198D03*
X159589Y817543D03*
X159688Y832484D03*
X159431Y838974D03*
X159688Y829234D03*
X159137Y820712D03*
X159688Y851564D03*
X159560Y842172D03*
X159426Y848357D03*
X662166Y456914D03*
X661760Y460089D03*
X646246Y475961D03*
X646794Y472634D03*
X682915Y467823D03*
X708059Y449951D03*
X671145Y454348D03*
X658195Y464248D03*
X653351Y470098D03*
X650837Y472421D03*
X646251Y479161D03*
X675745Y448189D03*
X735191Y453967D03*
X735231Y457167D03*
X746845Y476389D03*
Y473189D03*
X717993Y451389D03*
X731751Y464398D03*
X735259Y469898D03*
X721445Y455789D03*
X726589Y460909D03*
X743520Y478297D03*
X738745Y472789D03*
X713845Y447289D03*
G54D14*
X9243Y334400D03*
X8788Y453864D03*
X63400Y89300D03*
X51900Y83600D03*
X43980Y86200D03*
X68000Y87750D03*
X42700Y110500D03*
X67300Y107200D03*
X63100Y107300D03*
X51800Y93500D03*
X79600Y91500D03*
X51900Y89900D03*
X79500Y85700D03*
X77200Y95500D03*
X69800Y176800D03*
X31500Y185700D03*
X76250Y148850D03*
X70200Y199300D03*
X29600Y200100D03*
X26100Y187300D03*
X39800Y172900D03*
X27800Y191100D03*
X74700Y191700D03*
X70675Y145000D03*
X60009Y255077D03*
X55624Y255132D03*
X59523Y271123D03*
X60102Y263180D03*
X55883Y263570D03*
X33400Y266400D03*
X59258Y246890D03*
X60069Y237965D03*
X64700Y215100D03*
X51600Y217000D03*
X50500Y243100D03*
X70636Y272953D03*
X79189Y235119D03*
X76019Y222534D03*
X42507Y296616D03*
X59316Y300366D03*
X59096Y289139D03*
X59523Y281330D03*
X52257Y276649D03*
X55420Y288656D03*
X17100Y311700D03*
X61776Y367194D03*
X43345Y386857D03*
X43639Y374043D03*
X29700Y355000D03*
X27284Y358500D03*
X67527Y381818D03*
X51422Y473540D03*
X24315Y472668D03*
X47307Y465104D03*
X29064Y471345D03*
X55295Y479672D03*
X20928Y453864D03*
X21300Y468000D03*
X38800Y535700D03*
X38200Y528900D03*
X51383Y514037D03*
X63862Y512438D03*
X73542Y514340D03*
X37200Y513500D03*
X32026Y516764D03*
X60800Y505200D03*
X67244Y535455D03*
X72677Y528615D03*
X59379Y644787D03*
X57500Y662600D03*
X47000Y645300D03*
X60122Y747800D03*
X64000Y765600D03*
X47100Y746000D03*
X65447Y711413D03*
X62066Y711051D03*
X65356Y707010D03*
X61193Y706973D03*
X106300Y105900D03*
X81150Y120850D03*
X89400Y120800D03*
X85250Y120850D03*
X117500Y106200D03*
X85000Y107800D03*
X111700Y106100D03*
X89000Y107700D03*
X132500Y124600D03*
X83800Y188800D03*
X111482Y202800D03*
X113815Y194333D03*
X122400Y199000D03*
X80685Y192398D03*
X84641Y204036D03*
X93303Y154970D03*
X144950Y177338D03*
X85713Y151540D03*
X84900Y145300D03*
X125700Y225200D03*
X121000Y225300D03*
X109400Y225400D03*
X90813D03*
X79800Y225900D03*
X87227Y242891D03*
X87263Y264658D03*
X90652Y265960D03*
X87698Y246708D03*
X94051Y265872D03*
X91230Y247047D03*
X91819Y250396D03*
X94793Y252595D03*
X98211Y252758D03*
X142933Y251431D03*
X132651Y255357D03*
X138228Y260175D03*
X124933Y270414D03*
X136427Y251413D03*
X124874Y273953D03*
X137809Y247647D03*
X135592Y257933D03*
X116566Y254205D03*
X114229Y270684D03*
X119242Y252107D03*
X112042Y275903D03*
X121685Y249741D03*
X121741Y246341D03*
X118219Y274497D03*
X122572Y258147D03*
X121599Y274869D03*
X130567Y258051D03*
X113558Y261260D03*
X111008Y242830D03*
X106381Y259865D03*
X106504Y243329D03*
X103610Y268626D03*
X102713Y242975D03*
X103003Y260260D03*
X108652Y247260D03*
X107887Y266647D03*
X101242Y265901D03*
X100415Y246679D03*
X126611Y258265D03*
X84863Y229783D03*
X134529Y264470D03*
X137190Y266587D03*
X131901Y267444D03*
X132163Y271041D03*
X137690Y273752D03*
X110610Y206436D03*
X109534Y314564D03*
X92682Y331571D03*
X140103Y328216D03*
X117460Y335158D03*
X128964Y339470D03*
X148102Y338366D03*
X119603Y285731D03*
X124478Y280855D03*
X95202Y290958D03*
X98565Y290455D03*
X102107Y290439D03*
X105603Y291092D03*
X95146Y279609D03*
X110808Y291075D03*
X98546Y279609D03*
X114915Y290203D03*
X104413Y278608D03*
X117027Y278475D03*
X148834Y284832D03*
X107750Y277953D03*
X128918Y307533D03*
X135308Y276806D03*
X139784Y276432D03*
X142241Y278783D03*
X95400Y383083D03*
X118744Y525279D03*
X140399Y525238D03*
X129199Y525271D03*
X107103Y525057D03*
X95599Y525026D03*
X84799Y524898D03*
X90878Y585185D03*
X85654Y659044D03*
X83960Y632636D03*
X83500Y653600D03*
Y640044D03*
X84900Y747900D03*
X90746Y712435D03*
X90947Y709040D03*
X91003Y705214D03*
X91130Y701741D03*
X85300Y755100D03*
X85000Y775900D03*
X84100Y769000D03*
X220131Y58163D03*
X197900Y82000D03*
X201237Y106350D03*
X210356Y99104D03*
X210680Y84396D03*
X201614Y89932D03*
X212028Y93512D03*
X152350Y131084D03*
X204849Y106438D03*
X200100Y101200D03*
X170302Y147100D03*
X158100Y166800D03*
X160311Y141680D03*
X219548Y174651D03*
X189600Y166700D03*
X189700Y170200D03*
X190018Y173586D03*
X188961Y162715D03*
X167015Y167633D03*
X163550Y179657D03*
X172645Y179104D03*
X177087Y178920D03*
X183120Y266103D03*
X183082Y271969D03*
X182853Y256107D03*
X183956Y261452D03*
X168010Y267909D03*
X219717Y211198D03*
X182177Y251208D03*
X154300Y227900D03*
X171200Y233000D03*
X185563Y245456D03*
X175064Y232857D03*
X185740Y240983D03*
X185502Y237383D03*
X152663Y272053D03*
X192284Y258847D03*
X150666Y243134D03*
X195698Y259749D03*
X196365Y256414D03*
X168324Y246397D03*
X171762Y258345D03*
X167894Y243024D03*
X167760Y239626D03*
X183043Y276658D03*
X183707Y289861D03*
X183653Y283162D03*
X184188Y340638D03*
X162135Y332650D03*
X185042Y286734D03*
X167051Y293752D03*
X188273Y285674D03*
X187118Y281963D03*
X163142Y294193D03*
X172818Y288683D03*
X216178Y411331D03*
X219144Y414536D03*
X195307Y355649D03*
X206775Y348954D03*
X173508Y348462D03*
X177715Y397471D03*
X212500Y395500D03*
X217800Y395900D03*
X206871Y397177D03*
X210042Y412265D03*
X175767Y380311D03*
X189073Y380379D03*
X185276Y380362D03*
X181242Y380481D03*
X197565Y380257D03*
X203379Y380312D03*
X169600Y380500D03*
X173864Y397677D03*
X213400Y434601D03*
X181980Y458681D03*
X210772Y431456D03*
X200453Y439066D03*
X203186Y451492D03*
X180445Y422567D03*
X176991Y463723D03*
X184750Y427953D03*
X208947Y443700D03*
X196803Y444462D03*
X201400Y434400D03*
X202764Y444274D03*
X190887Y424438D03*
X174500Y424100D03*
X182060Y443776D03*
X180313Y446694D03*
X176915Y446556D03*
X195400Y452051D03*
X208632Y457048D03*
X181034Y427967D03*
X177700Y427300D03*
X184399Y525203D03*
X195499D03*
X206699D03*
X217899Y525103D03*
X162615Y525220D03*
X173537D03*
X151684Y525258D03*
X210223Y501477D03*
X213500Y503600D03*
X219590Y740816D03*
X254498Y88487D03*
X251687Y98033D03*
X261830Y81230D03*
X241101D03*
X256928Y69301D03*
X241132Y85023D03*
X242488Y88466D03*
X223948Y174292D03*
X251700Y135484D03*
X231350Y222067D03*
X223129Y210901D03*
X224664Y293860D03*
X257400Y403206D03*
X239600Y405600D03*
X237800Y411200D03*
X226576Y401835D03*
X228243Y380358D03*
X231915Y380533D03*
X244928Y367685D03*
X238151Y356092D03*
X228510Y367624D03*
X240715Y380333D03*
X222269Y402278D03*
X228949Y410741D03*
X225421Y410908D03*
X269840Y386256D03*
X261300Y402355D03*
X275500Y415400D03*
X264124Y408219D03*
X258267Y408800D03*
X233400Y409700D03*
X255010Y367624D03*
X273554Y386722D03*
X223600Y456200D03*
X246502Y472752D03*
X255622Y461532D03*
X263000Y438800D03*
X260600Y435900D03*
X258299Y432800D03*
X250400Y440000D03*
X249600Y428100D03*
X237700Y458000D03*
X279120Y440440D03*
X276761Y443421D03*
X277575Y449398D03*
X270714Y458323D03*
X263719Y455536D03*
X259779Y456823D03*
X220768Y418393D03*
X260322Y462288D03*
X256852Y465331D03*
X258221Y469246D03*
X235069Y464940D03*
X257184Y421241D03*
X271342Y440630D03*
X235600Y433300D03*
X264775Y459236D03*
X279789Y432846D03*
X285565Y438912D03*
X250400Y473300D03*
X260481Y473769D03*
X253214Y469048D03*
X228400Y486400D03*
X228001Y474064D03*
X226000Y458700D03*
X249845Y469508D03*
X229300Y442500D03*
X225700Y496800D03*
X226115Y507011D03*
X229513Y507141D03*
X232912Y507242D03*
X224515Y532633D03*
X237336Y531828D03*
X236700Y539300D03*
X240400Y534500D03*
X245800D03*
X241300Y539300D03*
X236300Y535600D03*
X243200Y531700D03*
X288586Y493703D03*
X268215Y490733D03*
X251755Y491731D03*
X270700Y495400D03*
X274315Y497133D03*
X283657Y532832D03*
X280259Y532714D03*
X232200Y492100D03*
X231739Y495469D03*
X248286Y489208D03*
X242100Y489000D03*
X228500Y498900D03*
X281183Y592936D03*
X223671Y740896D03*
X223129Y764830D03*
X271970Y798668D03*
X282413Y798410D03*
X228021Y787335D03*
X223596Y782163D03*
X236973Y795418D03*
X235169Y791455D03*
X240130Y789012D03*
X305456Y481787D03*
X335532Y485626D03*
X323215Y485633D03*
X304783Y467192D03*
X295115Y476433D03*
Y473033D03*
X297715Y479588D03*
X306603Y459523D03*
X301437Y426833D03*
X304200Y432600D03*
X300603Y432406D03*
X297238Y429641D03*
X304550Y424222D03*
X300059Y422844D03*
X318015Y493833D03*
X334315Y496733D03*
X330815Y493433D03*
X327115Y489533D03*
X344815Y494933D03*
X321415Y497133D03*
X304000Y538500D03*
X308800Y540925D03*
X324400Y570500D03*
X346510Y796385D03*
X350765D03*
X315696Y798445D03*
X294148Y798547D03*
X305437Y798205D03*
X362793Y77815D03*
Y126096D03*
X381025Y73748D03*
Y120650D03*
X373496Y140021D03*
X365131Y135484D03*
X428343Y463067D03*
X420575Y467336D03*
X382695Y467033D03*
Y471133D03*
X388884Y468631D03*
X387143Y462647D03*
X416588Y467839D03*
X361814Y796557D03*
X500295Y401715D03*
X501800Y387600D03*
X473838Y385675D03*
X474106Y382285D03*
X473605Y389068D03*
X499764Y411324D03*
X497279Y382551D03*
X435138Y460661D03*
X457091Y486699D03*
X501700Y477200D03*
X483530Y541762D03*
X487073Y554094D03*
X482183Y535169D03*
X483008Y500529D03*
X469932Y518034D03*
X447307Y511890D03*
X447090Y497242D03*
X471410Y490049D03*
X498994Y488322D03*
X501802Y490240D03*
X523200Y399400D03*
X506100Y380000D03*
X517041Y388700D03*
X536928Y411324D03*
X514000Y486293D03*
X508306Y428179D03*
X504500Y479500D03*
X514073Y552477D03*
X503300Y539700D03*
X637200Y393900D03*
X629100Y536000D03*
X632600Y555200D03*
X636200Y555100D03*
X640100Y550600D03*
X662100Y394600D03*
X667979Y486293D03*
X702400Y431500D03*
X698300Y431600D03*
X702000Y485700D03*
X688615Y485133D03*
X707700Y476500D03*
X707890Y467821D03*
X684259Y476130D03*
X682774Y449737D03*
X667745Y456089D03*
X662604Y463284D03*
X671915Y543133D03*
X694700Y547700D03*
X688800Y540450D03*
X702400Y554800D03*
X705927Y538650D03*
X663600Y535395D03*
X644600Y556700D03*
X652400Y545200D03*
X674375Y509826D03*
X700512Y510204D03*
X643833Y549325D03*
X702000Y546581D03*
X702400Y550600D03*
X684600Y542100D03*
X682015Y493633D03*
X669200Y559600D03*
X656817Y567131D03*
X697600Y560000D03*
X701400Y560200D03*
X643100Y589900D03*
X689945Y758289D03*
X667982Y739870D03*
X681402Y757754D03*
X663575Y742289D03*
X668987Y731465D03*
X691075Y820814D03*
X680480Y773302D03*
X678755Y784815D03*
X676727Y790555D03*
X679630Y795856D03*
X680239Y802378D03*
X682693Y806283D03*
X684732Y810518D03*
X669886Y786112D03*
X666516Y784722D03*
X686308Y834802D03*
X646342Y826469D03*
X685799Y770894D03*
X690211Y827401D03*
X683715Y852233D03*
X710727Y862002D03*
X678351Y854383D03*
X679332Y841866D03*
X681156Y844982D03*
X681542Y848361D03*
X722687Y120650D03*
X727300Y273200D03*
X758200Y338900D03*
X756700Y370600D03*
X762900Y387400D03*
X729700Y551500D03*
X729600Y540400D03*
X724000Y532600D03*
X722682Y538700D03*
X716300Y517125D03*
X719800Y525000D03*
X719866Y528656D03*
X751965Y522097D03*
X747886D03*
X757848Y513543D03*
X752874Y534854D03*
X737297Y517903D03*
X756523Y520272D03*
X749493Y535216D03*
X725100Y519600D03*
X746000Y549700D03*
X726800Y527400D03*
X723538Y526440D03*
X742607Y549481D03*
X752100Y506500D03*
X749500Y508800D03*
X742000Y505000D03*
X762275Y512870D03*
X744073Y522097D03*
X755862Y516303D03*
X756400Y508100D03*
X756272Y534995D03*
X763000Y490800D03*
X717879Y564572D03*
X737400Y576200D03*
X766358Y564600D03*
X727700Y584400D03*
X758400Y568500D03*
X742600Y577100D03*
X757600Y639700D03*
X746669Y740179D03*
X743653Y744114D03*
X741453Y748054D03*
X738850Y751989D03*
X734450Y755929D03*
X730967Y759864D03*
X724305Y770450D03*
X723678Y774016D03*
X727477Y775212D03*
X724733Y779559D03*
X730028Y782297D03*
X724859Y784497D03*
X742663Y788885D03*
X729988Y787114D03*
X739510Y795264D03*
X725239Y788970D03*
X745230Y793211D03*
X729486Y791416D03*
X742370Y799077D03*
X725407Y794540D03*
X747659Y796960D03*
X744790Y802781D03*
X749593Y803991D03*
X747556Y808994D03*
X749629Y812608D03*
X722443Y826463D03*
X721704Y829981D03*
X724858Y831254D03*
X723801Y834857D03*
X726332Y837128D03*
X733066Y836450D03*
X729250Y850000D03*
X721243Y850725D03*
X718263Y863827D03*
X724093Y840187D03*
X726776Y842277D03*
X733796Y854172D03*
G54D17*
X22980Y59055D03*
X30854D03*
X22980Y106299D03*
Y98425D03*
Y90551D03*
Y82677D03*
Y74803D03*
Y66929D03*
X30854Y98425D03*
Y90551D03*
Y82677D03*
Y74803D03*
Y66929D03*
X41142Y135669D03*
Y155669D03*
Y145669D03*
X26181Y537559D03*
Y527559D03*
Y517559D03*
X41142Y655669D03*
Y645669D03*
Y635669D03*
Y763780D03*
Y753780D03*
Y773780D03*
G54D19*
X45700Y61000D03*
X65500Y60800D03*
X75500D03*
X45900Y50000D03*
X65700Y49800D03*
X50800Y39500D03*
X70700Y45800D03*
X55800Y61300D03*
X59900Y40600D03*
X50500Y67700D03*
X70500Y72000D03*
X60800Y72500D03*
X57200Y175300D03*
X39600Y494800D03*
X38200Y490900D03*
X35100Y494400D03*
X33600Y512600D03*
X37329Y524472D03*
X33880Y526500D03*
X33921Y520414D03*
X87900Y47800D03*
X90900Y42400D03*
X80400Y47800D03*
X147500Y90200D03*
X142167Y106366D03*
X142101Y98650D03*
X111100Y75500D03*
X100000Y75600D03*
X121700Y75300D03*
X85300Y70200D03*
X126300Y180209D03*
X126700Y173500D03*
X136291Y179968D03*
X136100Y173800D03*
X134200Y217300D03*
X130000Y217200D03*
X134600Y222200D03*
X209100Y51700D03*
X191700Y63300D03*
X209200Y65100D03*
X200700Y51700D03*
X185100Y55900D03*
X208900Y58600D03*
X192000Y55900D03*
X200700Y58300D03*
X184700Y63100D03*
X154500Y90000D03*
X158000Y79600D03*
X165200Y79500D03*
X163300Y95900D03*
X163500Y105500D03*
X151800Y72400D03*
X209000Y72300D03*
X201500D03*
X177100Y99500D03*
X177200Y104800D03*
X177300Y94200D03*
Y88500D03*
X184700D03*
X190700Y77800D03*
X201200Y65600D03*
X191000Y71300D03*
X184500Y71200D03*
X177400Y71400D03*
X177500Y77900D03*
X183700Y78100D03*
X191500Y88500D03*
X204200Y126700D03*
X206600Y130300D03*
X201900D03*
X282282Y47189D03*
X286930D03*
X228635Y385956D03*
X232788Y385893D03*
X229764Y513034D03*
X234416Y512963D03*
X238924Y512390D03*
X243100Y516300D03*
X245963Y511890D03*
X250975Y511729D03*
X255500Y514000D03*
X264000Y513400D03*
X299300Y41300D03*
X321300Y43200D03*
X351800Y42200D03*
X360500Y42600D03*
X330000Y42800D03*
X329900Y37100D03*
X321300D03*
X360500Y36700D03*
X291373Y47394D03*
X299300Y46400D03*
X351800Y36300D03*
X320207Y428442D03*
X320166Y432442D03*
X380956Y408290D03*
X376513Y408085D03*
X371865D03*
X380392Y416962D03*
X375949Y416757D03*
X371301D03*
X366653Y416484D03*
X367217Y407812D03*
X366719Y424200D03*
X371367Y424473D03*
X376015D03*
X380458Y424678D03*
X410200Y474200D03*
X410179Y469769D03*
X438300Y481200D03*
X434515Y483333D03*
X434412Y479334D03*
X432014Y476132D03*
X633923Y520400D03*
X711500Y438300D03*
X644900Y538300D03*
X726000Y650700D03*
X720000Y650800D03*
X733000Y650600D03*
X740000D03*
X745413Y854763D03*
G54D22*
X54724Y557087D03*
Y620079D03*
Y675197D03*
Y738189D03*
X144843Y798779D03*
Y874449D03*
G54D26*
X276982Y828335D03*
X286982Y818335D03*
X276982D03*
X356982D03*
X346982D03*
X336982D03*
X326982D03*
X316982D03*
X306982D03*
X296982D03*
X366982D03*
G54D24*
X144843Y812994D03*
Y860234D03*
G54D16*
X6614Y553544D03*
X10551Y623622D03*
X6614Y671654D03*
X10551Y741732D03*
X18425Y553544D03*
X32204D03*
X18425Y623622D03*
X32204D03*
X18425Y671654D03*
X32204D03*
X18425Y741732D03*
X32204D03*
G54D27*
X314000Y405200D03*
X316800Y415900D03*
X299800Y398500D03*
X332600Y400100D03*
X413900Y396400D03*
X414894Y453432D03*
X419296Y449111D03*
X423572Y453454D03*
X419092Y457572D03*
X419225Y453324D03*
X428616Y429466D03*
X391500Y459000D03*
X399900Y458600D03*
X421273Y439381D03*
X475600Y462100D03*
X452300Y420900D03*
X458900Y446600D03*
X483100Y449900D03*
X488500Y474200D03*
X450300Y459900D03*
X471300Y482200D03*
X449000Y480000D03*
X438316Y449493D03*
X438294Y453811D03*
G54D11*
X-138100Y222300D03*
Y241300D03*
Y260300D03*
Y279300D03*
Y298300D03*
Y317300D03*
Y336300D03*
X-70100Y222300D03*
X-87100D03*
X-104100D03*
X-121100D03*
X-70100Y241300D03*
X-87100D03*
X-104100D03*
X-121100D03*
X-70100Y260300D03*
X-87100D03*
X-104100D03*
X-121100D03*
X-70100Y279300D03*
X-87100D03*
X-104100D03*
X-121100D03*
X-70100Y298300D03*
X-87100D03*
X-104100D03*
X-121100D03*
X-70100Y317300D03*
X-87100D03*
X-104100D03*
X-121100D03*
X-70100Y336300D03*
X-87100D03*
X-104100D03*
X-121100D03*
X4800Y48600D03*
X5800Y6400D03*
X5000Y71900D03*
Y91900D03*
X5100Y111800D03*
X4900Y130400D03*
X5000Y150500D03*
X5300Y170000D03*
X-2100Y222300D03*
X-19100D03*
X-36100D03*
X-53100D03*
X-2100Y241300D03*
X-19100D03*
X-36100D03*
X-53100D03*
X-2100Y260300D03*
X-19100D03*
X-36300Y260000D03*
X-53100Y260300D03*
X-1900Y288300D03*
X-49400Y284500D03*
X-19600Y279500D03*
X-36100Y279300D03*
X-2100Y298300D03*
X-19100D03*
X-36100D03*
X-53100D03*
X-2100Y317300D03*
X-19100D03*
X-36100D03*
X-53100D03*
X-2100Y336300D03*
X-19100D03*
X-36100D03*
X-53100D03*
X-1600Y413600D03*
Y394600D03*
Y375600D03*
Y356600D03*
X-52600Y413600D03*
X-35600D03*
X-18600D03*
X-52600Y394600D03*
X-35600D03*
X-18600D03*
X-52600Y375600D03*
X-35600D03*
X-18600D03*
X-52600Y356600D03*
X-35600D03*
X-18600D03*
X-19400Y483400D03*
X-2400D03*
X-36400D03*
X-53400D03*
X-1500Y470300D03*
Y451300D03*
Y432300D03*
X-52500Y470300D03*
X-35500D03*
X-18500D03*
X-52500Y451300D03*
X-35500D03*
X-18500D03*
X-52500Y432300D03*
X-35500D03*
X-18500D03*
X9151Y473051D03*
X8672Y487593D03*
X-19400Y502400D03*
X-2400D03*
X-36400D03*
X-53400D03*
X7075Y527972D03*
X7927Y509647D03*
X8140Y637282D03*
X8246Y771416D03*
X53200Y26300D03*
X50600Y6000D03*
X48100Y133900D03*
X59200Y95573D03*
X47900Y145500D03*
X48100Y153800D03*
X43800Y204800D03*
X38800Y194300D03*
X38700Y199700D03*
X73700D03*
X49500Y169300D03*
X61751Y181464D03*
X44100Y200600D03*
X49286Y203671D03*
X69000Y202700D03*
X77200Y189000D03*
X60200Y193550D03*
X43900Y209000D03*
X72001Y265901D03*
X69400Y207400D03*
X43181Y278603D03*
X39563Y307968D03*
X21876Y282289D03*
X41418Y287473D03*
X70775Y398396D03*
X70845Y405839D03*
X70952Y414050D03*
X54515Y396433D03*
X54463Y386651D03*
X70865Y390502D03*
X43569Y379314D03*
X65605Y367307D03*
X16158Y477255D03*
X79050Y457367D03*
X74805Y481031D03*
X66991Y476766D03*
X62798Y461555D03*
X74451Y465323D03*
X79094Y441620D03*
X74801Y433368D03*
X70869Y421840D03*
X70759Y449277D03*
X20715Y485712D03*
X20276Y477090D03*
X18809Y491871D03*
X17212Y532250D03*
X18064Y513925D03*
X78742Y488905D03*
X66961Y488885D03*
X74805Y492842D03*
X56121Y494271D03*
X21090Y497108D03*
X54659Y513125D03*
X67140Y511501D03*
X50893Y534434D03*
X66300Y548000D03*
X69569Y594959D03*
X69520Y560987D03*
X68421Y570392D03*
X69323Y579887D03*
X69518Y604727D03*
X69220Y614992D03*
X18277Y641560D03*
X9844Y658803D03*
X19981Y663081D03*
X68928Y687846D03*
X69316Y697605D03*
X69911Y676938D03*
X73900Y664900D03*
X77000Y646200D03*
X72930Y645818D03*
X67257Y643668D03*
X9631Y753837D03*
X19768Y758115D03*
X69558Y711913D03*
X68620Y722610D03*
X69217Y732676D03*
X73325Y760926D03*
X67809Y758190D03*
X18383Y775694D03*
X55459Y780063D03*
X48300Y775300D03*
X73282Y778907D03*
X124100Y6700D03*
X110800Y48800D03*
X120200Y48400D03*
X98700Y48900D03*
X143900Y38000D03*
X108100Y35300D03*
X146900Y48500D03*
X109700Y6400D03*
X119700Y35400D03*
X139800Y31100D03*
X96300Y6100D03*
X147200Y7300D03*
X108600Y19900D03*
X126500Y20100D03*
X82400Y89500D03*
X79900Y148700D03*
X103300Y160900D03*
X112000Y160700D03*
X119900Y162200D03*
X125300Y162300D03*
X122100Y203300D03*
X96900Y189286D03*
X107771Y182699D03*
X145400Y161955D03*
X114700Y157000D03*
X107672Y156597D03*
X98700Y156200D03*
X122200Y156700D03*
X80207Y139965D03*
X81200Y176000D03*
X125600Y221200D03*
X113863Y228669D03*
X102559Y228575D03*
X97885Y228339D03*
X147013Y225483D03*
X122000Y207300D03*
X94600Y206900D03*
X94548Y211258D03*
X106419Y310245D03*
X126184Y310860D03*
X93200Y308800D03*
X121477Y314973D03*
X135613Y308903D03*
X145795Y410173D03*
X149431Y394402D03*
X149783Y390487D03*
X110238Y410161D03*
X141738Y414098D03*
X133863Y413773D03*
X114175Y414098D03*
X122053D03*
X125990Y410161D03*
X94579Y406324D03*
X118130Y398511D03*
X98427Y410161D03*
X90553Y414098D03*
X86563Y402383D03*
X133964Y394555D03*
X102555Y394412D03*
X86616Y394413D03*
X86463Y390483D03*
X84200Y380000D03*
X145675Y473157D03*
Y465283D03*
X149719Y457328D03*
X129927Y473157D03*
Y465283D03*
X137801Y461346D03*
Y457409D03*
X114175Y473157D03*
X122053Y469220D03*
X110263Y469083D03*
X122053Y473157D03*
X90350Y473069D03*
X82679Y477094D03*
X90662Y461604D03*
X106263Y453483D03*
X106449Y465157D03*
X122053Y445598D03*
X126180Y418224D03*
X137801Y437720D03*
X137767Y425993D03*
X129927Y445598D03*
X141738Y449535D03*
X133864Y421972D03*
Y429846D03*
X98533Y418180D03*
X118134Y449362D03*
X106363Y441583D03*
X110238Y445598D03*
X110289Y422113D03*
X122053Y437720D03*
X114175D03*
X94661Y441681D03*
X106263Y433683D03*
X90544Y433408D03*
X90408Y421930D03*
X129927Y437720D03*
X141738Y488905D03*
X110238D03*
X125990D03*
X94377Y489070D03*
X91852Y563129D03*
X91156Y572112D03*
X90823Y581387D03*
X91343Y598284D03*
X91023Y606587D03*
X90923Y616187D03*
X90681Y690157D03*
X90174Y678675D03*
X85600Y647837D03*
X106051Y767209D03*
X93840Y699686D03*
X90814Y734451D03*
X91027Y724985D03*
X91094Y715818D03*
X84703Y758885D03*
X84182Y764879D03*
X122899Y825236D03*
X112762Y820958D03*
X116188Y771487D03*
X131900Y893200D03*
X120874Y857517D03*
X110737Y853239D03*
X131700Y915700D03*
X89871Y917500D03*
X173200Y10900D03*
X213700Y35200D03*
X186000D03*
X197796Y12653D03*
X160600Y49100D03*
X153200Y48700D03*
X167500Y49000D03*
X160500Y19700D03*
X170400Y31100D03*
X150600Y37800D03*
X212800Y125800D03*
X182400Y128300D03*
X175598Y128436D03*
X220100Y123600D03*
X166700Y128800D03*
X172200Y128300D03*
X179000D03*
X205628Y89404D03*
X211700Y181600D03*
X208200Y153500D03*
X203900D03*
X200100Y146500D03*
Y150400D03*
X199100Y153800D03*
X194800D03*
X207495Y192761D03*
X169800Y155796D03*
X165162Y155909D03*
X169709Y160049D03*
X165388Y160094D03*
X174339Y151172D03*
X178400Y152300D03*
X156800Y230500D03*
X152663Y267791D03*
X216335Y218212D03*
X196344Y237383D03*
X196078Y248183D03*
X196021Y244556D03*
X196151Y240983D03*
X151519Y250193D03*
X180641Y231683D03*
X186319Y268076D03*
X183466Y294017D03*
X152580Y285530D03*
X203410Y394323D03*
X182378Y390377D03*
X157574Y394185D03*
X161241Y398226D03*
X161277Y414114D03*
X174124Y402624D03*
X161213Y390551D03*
X169503Y386977D03*
X200161Y416474D03*
X206142Y413945D03*
X211243Y462005D03*
X161423Y484968D03*
Y481031D03*
X157486Y473157D03*
X165360Y469220D03*
X153549Y477094D03*
X173234Y465283D03*
Y453472D03*
X203406Y454885D03*
X174086Y484839D03*
X195038Y477148D03*
X175150Y476294D03*
X174351Y429014D03*
X161423Y437720D03*
X153549Y433783D03*
X161363Y425780D03*
X173234Y437720D03*
X173155Y417978D03*
X153422Y441722D03*
X216300Y499600D03*
X157486Y488905D03*
X165360D03*
X169297Y492842D03*
X161423D03*
X193016Y496643D03*
X219492Y517832D03*
X196400Y585300D03*
X179000Y624800D03*
X193600Y702400D03*
X179100Y714600D03*
X202300Y742000D03*
X157422Y825918D03*
X158725Y835536D03*
X181642Y837321D03*
Y827853D03*
X181772Y818429D03*
X159926Y813000D03*
X201663Y827680D03*
X201142Y837191D03*
X189273Y902478D03*
X213138Y905780D03*
X218729Y857629D03*
X160735Y857183D03*
X154730Y847010D03*
X181081Y856307D03*
X181124Y847013D03*
X200798Y846849D03*
X200460Y913771D03*
X233900Y32500D03*
X266700Y46900D03*
X263000Y47000D03*
X257500Y46900D03*
X253800Y47000D03*
X244900Y47300D03*
X248600Y47200D03*
X252187Y23895D03*
X286651Y14571D03*
X224431Y15210D03*
X248900Y8400D03*
X235000Y47500D03*
X238700Y47400D03*
X225231Y58420D03*
X282444Y106834D03*
X225919Y88394D03*
X225937Y80731D03*
X221710Y80767D03*
X221722Y88431D03*
X230158Y88359D03*
X230123Y80805D03*
X225851Y73774D03*
X221740Y73844D03*
X229870Y73970D03*
X228169Y68374D03*
X224169Y68520D03*
X228728Y96613D03*
X224285Y96750D03*
X259815Y94233D03*
X248000Y114500D03*
X246100Y151300D03*
Y155800D03*
Y160400D03*
X258741Y193852D03*
X231049Y188760D03*
X256823Y221979D03*
X246169Y246270D03*
X230774Y270268D03*
X241694Y274956D03*
X238614Y217763D03*
X222496Y222320D03*
X239693Y396029D03*
X257500Y399300D03*
X264600Y380500D03*
X270800Y408500D03*
X269300Y486200D03*
X249600Y432500D03*
X239000Y440300D03*
X244800Y454500D03*
X229600Y460700D03*
X289200Y445100D03*
X252200Y486700D03*
X290300Y462400D03*
X290011Y456234D03*
X289000Y449200D03*
X221035Y453935D03*
X268600Y529800D03*
X256300Y531400D03*
X289400Y511700D03*
X243300Y527900D03*
X247256Y529218D03*
X251700Y531500D03*
X268500Y525800D03*
X238118Y492166D03*
X246132Y492160D03*
X289405Y515437D03*
X277300Y572500D03*
X259600Y568400D03*
X271949Y648699D03*
X272588Y681087D03*
X244248Y682153D03*
X255542Y665532D03*
X241904Y652321D03*
X289634Y659352D03*
X284520Y743307D03*
X282176Y713475D03*
X228249Y761450D03*
X230823Y823850D03*
X237950Y774979D03*
X237815Y779065D03*
X226949Y782735D03*
X253623Y867319D03*
X254262Y899707D03*
X225922Y900773D03*
X237216Y884152D03*
X223578Y870941D03*
X285585Y897363D03*
X283241Y867531D03*
X264212Y903112D03*
X277254Y852624D03*
X299600Y62100D03*
X351900Y62000D03*
X360200Y62300D03*
X329500Y62600D03*
X321300Y63100D03*
X325006Y15636D03*
X299500Y68200D03*
X352000Y68000D03*
X360200Y68200D03*
X329600D03*
X321400Y68500D03*
X344663Y108965D03*
X312275Y98098D03*
X354197Y158187D03*
X301140Y161383D03*
X352066Y262596D03*
X307320Y223390D03*
X301781Y258122D03*
X322022Y279856D03*
X309200Y444700D03*
X331800Y440400D03*
X331900Y444600D03*
X356700Y437500D03*
X348800D03*
X341500Y437400D03*
X291300Y468600D03*
X308900Y449100D03*
X327900Y438100D03*
X341430Y459351D03*
X345735Y460843D03*
X349800Y460000D03*
X353698Y460323D03*
X357812Y460406D03*
X350400Y512000D03*
X335600Y511400D03*
X304700Y509500D03*
X317900Y520100D03*
X314628Y517729D03*
X343905Y519116D03*
X309648Y582024D03*
X319679Y655730D03*
X320318Y688118D03*
X291978Y689184D03*
X303272Y672563D03*
X347378Y688332D03*
X358672Y671711D03*
X345034Y658500D03*
X302115Y693462D03*
X360803Y704312D03*
X333102Y737766D03*
X344396Y721145D03*
X330758Y707934D03*
X312221Y709853D03*
X312860Y742241D03*
X295814Y726686D03*
X319171Y767846D03*
X313959Y724732D03*
X354623Y896937D03*
X352279Y867105D03*
X313286Y863909D03*
X313925Y896297D03*
X296879Y880742D03*
X332436Y858576D03*
X337648Y901690D03*
X382100Y61900D03*
X401343Y58465D03*
X394098Y20059D03*
X362775D03*
X412506Y33484D03*
X382200Y68500D03*
X410025Y87658D03*
X390208Y180135D03*
X366982Y198886D03*
X407769Y204757D03*
X384668Y247681D03*
X376144Y279856D03*
X378700Y437600D03*
X371200Y437800D03*
X363800Y437700D03*
X361533Y460222D03*
X365241Y460010D03*
X375079Y654878D03*
X375718Y687266D03*
X430267Y679595D03*
X413860Y696428D03*
X400222Y683217D03*
X388817Y692040D03*
X420252Y725194D03*
X420891Y757582D03*
X392551Y758648D03*
X403845Y742027D03*
X390207Y728816D03*
X361442Y736700D03*
X430906Y711983D03*
X402566Y713049D03*
X395450Y767846D03*
X378868Y723311D03*
X421530Y814262D03*
X419186Y784430D03*
X429202Y894806D03*
X426858Y864974D03*
X382324Y863483D03*
X382963Y895871D03*
X365917Y880316D03*
X413927Y901690D03*
X397345Y857155D03*
X432682Y23909D03*
X472315Y23056D03*
X496393Y55871D03*
X457399Y46069D03*
X496109Y93412D03*
X457989Y78967D03*
X493200Y145500D03*
X451789Y154565D03*
X473097Y208901D03*
X453252Y250240D03*
X500526Y394177D03*
X494400Y493600D03*
Y497500D03*
X455846Y546626D03*
X471650Y493916D03*
X494410Y501344D03*
X458713Y518034D03*
X482200Y529100D03*
X484200Y538000D03*
X483800Y545700D03*
X452652Y495705D03*
X465900Y501200D03*
X465212Y726260D03*
X465851Y758648D03*
X437511Y759714D03*
X448805Y743093D03*
X435167Y729882D03*
X474587Y765253D03*
X445197Y719047D03*
X449231Y780808D03*
X449870Y813196D03*
X432824Y797641D03*
X476931Y795085D03*
X488225Y778464D03*
X499945Y828325D03*
X486307Y815114D03*
X456903Y861352D03*
X457542Y893740D03*
X440496Y878185D03*
X488651Y844946D03*
X499208Y899795D03*
X463674Y852891D03*
X557547Y24335D03*
X526213Y34431D03*
X555558Y100229D03*
X531425Y77545D03*
X545330Y147959D03*
X521476Y205704D03*
X509632Y174434D03*
X526688Y248818D03*
X513500Y399060D03*
X520900Y388100D03*
X523462Y423957D03*
X503923Y423910D03*
X536736Y418540D03*
X529000Y550500D03*
X566000Y536700D03*
X502318Y535328D03*
X521002Y555911D03*
X525300Y552800D03*
X516900Y561200D03*
X528000Y562900D03*
X512700Y560000D03*
X508224Y580873D03*
X549379Y653173D03*
X504632Y761631D03*
X505271Y794019D03*
X516352Y811492D03*
X562377Y833013D03*
X532332Y836635D03*
X516991Y843880D03*
X563016Y865401D03*
X534676Y866467D03*
X545970Y849846D03*
X545118Y880530D03*
X528711Y897363D03*
X515073Y884152D03*
X562590Y881808D03*
X510579Y854786D03*
X545757Y912918D03*
X517417Y913984D03*
X564934Y911640D03*
X573457Y59531D03*
X621826Y20111D03*
X591122Y33010D03*
X607704Y77545D03*
X586385Y204283D03*
X596334Y173012D03*
X602967Y248818D03*
X638300Y511800D03*
X641800Y519000D03*
X639500Y521900D03*
X641700Y510300D03*
X587942Y582024D03*
X614582Y653599D03*
X604141Y675547D03*
X578784Y682152D03*
X582620Y653386D03*
X632693Y697281D03*
X607550Y703460D03*
X628006Y720720D03*
X592635Y878186D03*
X576228Y895019D03*
X640791Y876268D03*
X641430Y908656D03*
X613090Y909722D03*
X624384Y893101D03*
X610746Y879890D03*
X593274Y910574D03*
X660180Y56547D03*
X657451Y28746D03*
X703700Y30300D03*
X651658Y95968D03*
X692985Y75650D03*
X699619Y201914D03*
X652714Y200019D03*
X692512Y162589D03*
X661673Y260892D03*
X688248Y246923D03*
X712386Y297542D03*
X693509Y431701D03*
X689111Y431612D03*
X684869Y431611D03*
X680738Y431633D03*
X651000Y467700D03*
X646163Y482677D03*
X643296Y477617D03*
X643914Y470592D03*
X648652Y470028D03*
X654990Y463513D03*
X658399Y460842D03*
X659485Y455066D03*
X666818Y452921D03*
X694995Y453626D03*
X694923Y461253D03*
X694851Y469456D03*
X694907Y476993D03*
X710645Y447266D03*
X678767Y447136D03*
X672583Y467901D03*
X667831Y479556D03*
X711409Y467621D03*
X665499Y556600D03*
X651800Y540295D03*
X711400Y515400D03*
X711900Y521500D03*
X675400Y538100D03*
X662200Y547300D03*
X709600Y524100D03*
X668135Y523360D03*
X672161Y528021D03*
X676550Y523677D03*
X672342Y519560D03*
X672257Y523769D03*
X658314Y526697D03*
X672168Y538889D03*
X676115Y542633D03*
X685815Y496140D03*
X689996Y496274D03*
X694169Y496394D03*
X698475Y496387D03*
X702670Y496148D03*
X707296Y496348D03*
X712102Y542133D03*
X707589Y515400D03*
X700900Y539500D03*
X707391Y564566D03*
X678293Y698772D03*
X675736Y657222D03*
X694061Y681726D03*
X654641Y691101D03*
X643987Y664041D03*
X697897Y662763D03*
X708231Y730948D03*
X681276Y722211D03*
X650805Y716671D03*
X698962Y707936D03*
X700989Y759255D03*
X711116Y796516D03*
X702290Y820921D03*
X692356Y875629D03*
X692995Y908017D03*
X664655Y909083D03*
X675949Y892462D03*
X662311Y879251D03*
X754800Y56800D03*
Y36800D03*
Y16800D03*
X723466Y60810D03*
X721334Y17767D03*
X754800Y76800D03*
X754700Y117600D03*
Y97600D03*
X734333Y88085D03*
X754700Y197600D03*
Y177600D03*
Y157600D03*
Y137600D03*
Y257600D03*
Y237600D03*
Y217600D03*
Y277600D03*
X753800Y303200D03*
X767300Y340400D03*
X766900Y333754D03*
X735134Y289819D03*
X767000Y410900D03*
X766700Y403500D03*
X766900Y395400D03*
Y387800D03*
Y364600D03*
Y356300D03*
X767600Y348500D03*
X716700Y445400D03*
X742200Y472500D03*
X724300Y454000D03*
X719100Y478900D03*
X767400Y481600D03*
Y465900D03*
X767500Y450800D03*
X767300Y441747D03*
X766500Y435100D03*
X766800Y427000D03*
X767100Y418700D03*
X744986Y481255D03*
X749974Y477780D03*
X749628Y471196D03*
X739751Y469686D03*
X735295Y463720D03*
X738636Y457903D03*
X731780Y452531D03*
X729478Y459116D03*
X721600Y451000D03*
X719700Y485600D03*
X768000Y457700D03*
X767700Y473300D03*
X767100Y544600D03*
X766800Y535700D03*
X767200Y524500D03*
X766900Y497700D03*
X767200Y489700D03*
X767100Y623900D03*
Y614800D03*
X766700Y606900D03*
X767700Y600200D03*
X766700Y592700D03*
X767000Y584300D03*
Y576100D03*
Y569500D03*
X725900Y561800D03*
X766900Y639500D03*
Y631900D03*
X715795Y697494D03*
X750300Y663000D03*
X740513Y687906D03*
X756100Y658700D03*
X745733Y713048D03*
X764200Y813000D03*
X716221Y876694D03*
X729859Y889905D03*
X718565Y906526D03*
X746905Y905460D03*
X746266Y873072D03*
X745100Y859405D03*
X721112Y854419D03*
G54D18*
X29528Y19685D03*
X76772D03*
X108268Y905512D03*
X155512D03*
G54D21*
X53547Y322486D03*
Y302486D03*
X182681Y580832D03*
Y560832D03*
G54D13*
X-33503Y269685D03*
G54D28*
X716535Y39370D03*
G54D10*
X-1011811Y-15748D03*
Y940945D03*
X775591Y-15748D03*
Y940944D03*
G54D12*
X-59094Y277559D03*
X-7913D03*
G54D20*
X30854Y106299D03*
G54D25*
X286982Y828335D03*
X356982D03*
X346982D03*
X336982D03*
X326982D03*
X316982D03*
X306982D03*
X296982D03*
X366982D03*
G54D23*
X109410Y796831D03*
Y876397D03*
X168465Y796831D03*
Y876397D03*
%LPC*%
G75*
G54D30*
G01X-755164Y-252763D02*
Y-235263D01*
G01X-746868D02*
X-755164Y-246055D01*
G01X-745558Y-252763D02*
X-751453Y-241097D01*
G01X-737883Y-252763D02*
Y-235263D01*
X-727839Y-252763D01*
Y-235263D01*
G01X-715361Y-252763D02*
X-717108Y-252471D01*
X-718636Y-251305D01*
X-719946Y-249555D01*
X-720820Y-247513D01*
X-721256Y-245180D01*
Y-242846D01*
X-720820Y-240513D01*
X-719946Y-238471D01*
X-718636Y-236722D01*
X-717108Y-235555D01*
X-715361Y-235263D01*
X-713615Y-235555D01*
X-712086Y-236722D01*
X-710776Y-238471D01*
X-709902Y-240513D01*
X-709466Y-242846D01*
Y-245180D01*
X-709902Y-247513D01*
X-710776Y-249555D01*
X-712086Y-251305D01*
X-713615Y-252471D01*
X-715361Y-252763D01*
G01X-702446D02*
X-693276Y-235263D01*
G01X-702446D02*
X-693276Y-252763D01*
G01X-658494D02*
X-667228D01*
Y-235263D01*
X-658494D01*
G01X-661988Y-243721D02*
X-667228D01*
G01X-649946Y-252763D02*
X-640776Y-235263D01*
G01X-649946D02*
X-640776Y-252763D01*
G01X-632228D02*
Y-235263D01*
X-626988D01*
X-625241Y-236138D01*
X-623931Y-238180D01*
X-623494Y-240513D01*
X-623931Y-242846D01*
X-625023Y-244596D01*
X-626988Y-245472D01*
X-632228D01*
G01X-615820Y-252763D02*
X-610361Y-235263D01*
X-604902Y-252763D01*
G01X-606868Y-246638D02*
X-613855D01*
G01X-597883Y-252763D02*
Y-235263D01*
X-587839Y-252763D01*
Y-235263D01*
G01X-580164Y-252763D02*
Y-235263D01*
X-575798D01*
X-574051Y-236138D01*
X-572741Y-237305D01*
X-571649Y-239054D01*
X-570776Y-241097D01*
X-570558Y-244013D01*
X-570776Y-246930D01*
X-571649Y-248972D01*
X-572741Y-250722D01*
X-574051Y-251888D01*
X-575798Y-252763D01*
X-580164D01*
G01X-553494D02*
X-562228D01*
Y-235263D01*
X-553494D01*
G01X-556988Y-243721D02*
X-562228D01*
G01X-544728Y-252763D02*
Y-235263D01*
X-539269D01*
X-537523Y-236138D01*
X-536431Y-237305D01*
X-535994Y-239638D01*
X-536431Y-241972D01*
X-537741Y-243430D01*
X-539269Y-244305D01*
X-544728D01*
G01X-539269D02*
X-535994Y-252763D01*
G01X-503615Y-243430D02*
X-502741Y-242555D01*
X-502086Y-241097D01*
X-501649Y-239054D01*
X-502086Y-237305D01*
X-502959Y-236138D01*
X-504488Y-235263D01*
X-510383D01*
Y-252763D01*
X-503178D01*
X-501649Y-251597D01*
X-500776Y-249846D01*
X-500339Y-247805D01*
X-500776Y-245763D01*
X-502086Y-244013D01*
X-503615Y-243430D01*
X-510383D01*
G01X-487861Y-252763D02*
X-489608Y-252471D01*
X-491136Y-251305D01*
X-492446Y-249555D01*
X-493320Y-247513D01*
X-493756Y-245180D01*
Y-242846D01*
X-493320Y-240513D01*
X-492446Y-238471D01*
X-491136Y-236722D01*
X-489608Y-235555D01*
X-487861Y-235263D01*
X-486115Y-235555D01*
X-484586Y-236722D01*
X-483276Y-238471D01*
X-482402Y-240513D01*
X-481966Y-242846D01*
Y-245180D01*
X-482402Y-247513D01*
X-483276Y-249555D01*
X-484586Y-251305D01*
X-486115Y-252471D01*
X-487861Y-252763D01*
G01X-475820D02*
X-470361Y-235263D01*
X-464902Y-252763D01*
G01X-466868Y-246638D02*
X-473855D01*
G01X-457228Y-252763D02*
Y-235263D01*
X-451769D01*
X-450023Y-236138D01*
X-448931Y-237305D01*
X-448494Y-239638D01*
X-448931Y-241972D01*
X-450241Y-243430D01*
X-451769Y-244305D01*
X-457228D01*
G01X-451769D02*
X-448494Y-252763D01*
G01X-440164D02*
Y-235263D01*
X-435798D01*
X-434051Y-236138D01*
X-432741Y-237305D01*
X-431649Y-239054D01*
X-430776Y-241097D01*
X-430558Y-244013D01*
X-430776Y-246930D01*
X-431649Y-248972D01*
X-432741Y-250722D01*
X-434051Y-251888D01*
X-435798Y-252763D01*
X-440164D01*
G01X-633538Y-207763D02*
Y-190263D01*
X-627861Y-204846D01*
X-622184Y-190263D01*
Y-207763D01*
G01X-610361D02*
X-611671Y-207471D01*
X-612981Y-206305D01*
X-613855Y-204263D01*
X-614291Y-201930D01*
X-613855Y-199596D01*
X-612981Y-197555D01*
X-611671Y-196388D01*
X-610361Y-196097D01*
X-609051Y-196388D01*
X-607741Y-197555D01*
X-606868Y-199596D01*
X-606649Y-201930D01*
X-606868Y-204263D01*
X-607741Y-206305D01*
X-609051Y-207471D01*
X-610361Y-207763D01*
G01X-588931Y-190263D02*
Y-207763D01*
G01Y-205139D02*
X-589804Y-206597D01*
X-591115Y-207471D01*
X-592643Y-207763D01*
X-594389Y-207180D01*
X-595699Y-205722D01*
X-596573Y-203972D01*
X-596791Y-201930D01*
X-596573Y-199888D01*
X-595699Y-198138D01*
X-594389Y-196680D01*
X-592643Y-196097D01*
X-591115Y-196388D01*
X-590023Y-196972D01*
X-588931Y-198138D01*
G01X-578636Y-199888D02*
X-571649D01*
X-572304Y-197846D01*
X-573396Y-196680D01*
X-574924Y-196097D01*
X-576453Y-196388D01*
X-577763Y-197263D01*
X-578636Y-199305D01*
X-579073Y-201055D01*
Y-202805D01*
X-578636Y-204555D01*
X-577544Y-206305D01*
X-576234Y-207471D01*
X-574706Y-207763D01*
X-573178Y-207180D01*
X-571649Y-205430D01*
G01X-557861Y-207763D02*
Y-190263D01*
G01X-380161Y-252763D02*
Y-235263D01*
X-382781Y-238763D01*
G01Y-252763D02*
X-377541D01*
G01X-366809Y-238180D02*
X-365499Y-236430D01*
X-363971Y-235555D01*
X-362224Y-235263D01*
X-360041Y-235846D01*
X-358513Y-237305D01*
X-358076Y-239054D01*
X-358294Y-240805D01*
X-359168Y-242263D01*
X-363534Y-245180D01*
X-365499Y-247221D01*
X-366809Y-250139D01*
X-367246Y-252763D01*
X-358076D01*
G01X-345161Y-235263D02*
X-346908Y-235846D01*
X-348218Y-237305D01*
X-349091Y-239054D01*
X-349746Y-241388D01*
X-349964Y-244013D01*
X-349746Y-246638D01*
X-349091Y-248972D01*
X-348218Y-250722D01*
X-346908Y-252180D01*
X-345161Y-252763D01*
X-343415Y-252180D01*
X-342104Y-250722D01*
X-341231Y-248972D01*
X-340576Y-246638D01*
X-340358Y-244013D01*
X-340576Y-241388D01*
X-341231Y-239054D01*
X-342104Y-237305D01*
X-343415Y-235846D01*
X-345161Y-235263D01*
G01X-327661D02*
X-329408Y-235846D01*
X-330718Y-237305D01*
X-331591Y-239054D01*
X-332246Y-241388D01*
X-332464Y-244013D01*
X-332246Y-246638D01*
X-331591Y-248972D01*
X-330718Y-250722D01*
X-329408Y-252180D01*
X-327661Y-252763D01*
X-325915Y-252180D01*
X-324604Y-250722D01*
X-323731Y-248972D01*
X-323076Y-246638D01*
X-322858Y-244013D01*
X-323076Y-241388D01*
X-323731Y-239054D01*
X-324604Y-237305D01*
X-325915Y-235846D01*
X-327661Y-235263D01*
G01X-307541Y-252763D02*
Y-235263D01*
X-315620Y-247805D01*
X-304702D01*
G01X-393278Y-207763D02*
Y-190263D01*
X-388038D01*
X-386291Y-191138D01*
X-384981Y-193180D01*
X-384544Y-195513D01*
X-384981Y-197846D01*
X-386073Y-199596D01*
X-388038Y-200472D01*
X-393278D01*
G01X-366608Y-191722D02*
X-367918Y-190846D01*
X-369446Y-190263D01*
X-371193D01*
X-373158Y-191138D01*
X-374686Y-192596D01*
X-375778Y-194347D01*
X-376651Y-197263D01*
X-376870Y-199888D01*
X-376433Y-202513D01*
X-375778Y-204263D01*
X-374468Y-206013D01*
X-372939Y-207180D01*
X-371411Y-207763D01*
X-369883D01*
X-368354Y-207180D01*
X-367044Y-206305D01*
X-365952Y-205139D01*
G01X-352165Y-198430D02*
X-351291Y-197555D01*
X-350636Y-196097D01*
X-350199Y-194054D01*
X-350636Y-192305D01*
X-351509Y-191138D01*
X-353038Y-190263D01*
X-358933D01*
Y-207763D01*
X-351728D01*
X-350199Y-206597D01*
X-349326Y-204846D01*
X-348889Y-202805D01*
X-349326Y-200763D01*
X-350636Y-199013D01*
X-352165Y-198430D01*
X-358933D01*
G01X-342961Y-213596D02*
X-329861D01*
G01X-323933Y-207763D02*
Y-190263D01*
X-313889Y-207763D01*
Y-190263D01*
G01X-301411Y-207763D02*
X-303158Y-207471D01*
X-304686Y-206305D01*
X-305996Y-204555D01*
X-306870Y-202513D01*
X-307306Y-200180D01*
Y-197846D01*
X-306870Y-195513D01*
X-305996Y-193471D01*
X-304686Y-191722D01*
X-303158Y-190555D01*
X-301411Y-190263D01*
X-299665Y-190555D01*
X-298136Y-191722D01*
X-296826Y-193471D01*
X-295952Y-195513D01*
X-295516Y-197846D01*
Y-200180D01*
X-295952Y-202513D01*
X-296826Y-204555D01*
X-298136Y-206305D01*
X-299665Y-207471D01*
X-301411Y-207763D01*
G01X-218861Y-252763D02*
Y-235263D01*
X-221481Y-238763D01*
G01Y-252763D02*
X-216241D01*
G01X-250570Y-190263D02*
X-245111Y-207763D01*
X-239652Y-190263D01*
G01X-223244Y-207763D02*
X-231978D01*
Y-190263D01*
X-223244D01*
G01X-226738Y-198721D02*
X-231978D01*
G01X-214478Y-207763D02*
Y-190263D01*
X-209019D01*
X-207273Y-191138D01*
X-206181Y-192305D01*
X-205744Y-194638D01*
X-206181Y-196972D01*
X-207491Y-198430D01*
X-209019Y-199305D01*
X-214478D01*
G01X-209019D02*
X-205744Y-207763D01*
G01X-192611Y-208346D02*
X-193048Y-208055D01*
Y-207471D01*
X-192611Y-207180D01*
X-192174Y-207471D01*
Y-208055D01*
X-192611Y-208346D01*
G01X-38294Y-235263D02*
Y-252763D01*
X-47028D01*
G01X-59724D02*
X-60161Y-248972D01*
X-60816Y-245763D01*
X-61689Y-242846D01*
X-62781Y-239638D01*
X-64528Y-235263D01*
X-55794D01*
G01X-78971Y-244013D02*
X-83338D01*
Y-249263D01*
X-82028Y-251013D01*
X-80499Y-252180D01*
X-78316Y-252763D01*
X-76133Y-252180D01*
X-74604Y-251013D01*
X-73294Y-249263D01*
X-72421Y-247221D01*
X-71984Y-244888D01*
Y-242846D01*
X-72421Y-241097D01*
X-73294Y-239054D01*
X-74604Y-237305D01*
X-75914Y-236138D01*
X-77661Y-235263D01*
X-79189D01*
X-80936Y-235846D01*
X-82246Y-237013D01*
G01X-90139Y-252763D02*
Y-235263D01*
X-100183Y-252763D01*
Y-235263D01*
G01X-107858Y-252763D02*
Y-235263D01*
X-112224D01*
X-113971Y-236138D01*
X-115281Y-237305D01*
X-116373Y-239054D01*
X-117246Y-241097D01*
X-117464Y-244013D01*
X-117246Y-246930D01*
X-116373Y-248972D01*
X-115281Y-250722D01*
X-113971Y-251888D01*
X-112224Y-252763D01*
X-107858D01*
G01X-125778Y-190263D02*
Y-207763D01*
X-117044D01*
G01X-99981D02*
Y-196097D01*
G01Y-198138D02*
X-100854Y-196972D01*
X-102165Y-196388D01*
X-103693Y-196097D01*
X-105221Y-196680D01*
X-106531Y-197846D01*
X-107405Y-199596D01*
X-107841Y-201930D01*
X-107405Y-204263D01*
X-106531Y-206013D01*
X-105221Y-207180D01*
X-103693Y-207763D01*
X-102165Y-207471D01*
X-100854Y-206597D01*
X-99981Y-205430D01*
G01X-90996Y-213013D02*
X-89686Y-213596D01*
X-87939Y-213013D01*
X-86848Y-211847D01*
X-85974Y-210388D01*
X-84665Y-205722D01*
X-81826Y-196097D01*
G01X-88813D02*
X-84665Y-205722D01*
G01X-72186Y-199888D02*
X-65199D01*
X-65854Y-197846D01*
X-66946Y-196680D01*
X-68474Y-196097D01*
X-70003Y-196388D01*
X-71313Y-197263D01*
X-72186Y-199305D01*
X-72623Y-201055D01*
Y-202805D01*
X-72186Y-204555D01*
X-71094Y-206305D01*
X-69784Y-207471D01*
X-68256Y-207763D01*
X-66728Y-207180D01*
X-65199Y-205430D01*
G01X-54468Y-207763D02*
Y-196097D01*
G01Y-198430D02*
X-53376Y-197263D01*
X-52284Y-196388D01*
X-50756Y-196097D01*
X-49665Y-196388D01*
X-48354Y-197263D01*
G01X-37186Y-205722D02*
X-36094Y-206888D01*
X-34566Y-207763D01*
X-33256D01*
X-31946Y-207180D01*
X-31073Y-206305D01*
X-30636Y-205139D01*
X-30854Y-203388D01*
X-31728Y-202513D01*
X-35658Y-200763D01*
X-36531Y-198721D01*
X-36094Y-197263D01*
X-35221Y-196388D01*
X-33911Y-196097D01*
X-32601Y-196388D01*
X-31291Y-197263D01*
G01X51772Y-235263D02*
Y-252763D01*
X60506D01*
G01X68836Y-235263D02*
Y-247805D01*
X69709Y-250430D01*
X71456Y-252180D01*
X73639Y-252763D01*
X75822Y-252180D01*
X77569Y-250430D01*
X78442Y-247805D01*
Y-235263D01*
G01X95942Y-236722D02*
X94632Y-235846D01*
X93104Y-235263D01*
X91357D01*
X89392Y-236138D01*
X87864Y-237596D01*
X86772Y-239347D01*
X85899Y-242263D01*
X85680Y-244888D01*
X86117Y-247513D01*
X86772Y-249263D01*
X88082Y-251013D01*
X89611Y-252180D01*
X91139Y-252763D01*
X92667D01*
X94196Y-252180D01*
X95506Y-251305D01*
X96598Y-250139D01*
G01X103836Y-252763D02*
Y-235263D01*
G01X112132D02*
X103836Y-246055D01*
G01X113442Y-252763D02*
X107547Y-241097D01*
G01X126139Y-252763D02*
Y-244888D01*
X121772Y-235263D01*
G01X130506D02*
X126139Y-244888D01*
G01X25086Y-207763D02*
Y-190263D01*
X29452D01*
X31199Y-191138D01*
X32509Y-192305D01*
X33601Y-194054D01*
X34474Y-196097D01*
X34692Y-199013D01*
X34474Y-201930D01*
X33601Y-203972D01*
X32509Y-205722D01*
X31199Y-206888D01*
X29452Y-207763D01*
X25086D01*
G01X44114Y-199888D02*
X51101D01*
X50446Y-197846D01*
X49354Y-196680D01*
X47826Y-196097D01*
X46297Y-196388D01*
X44987Y-197263D01*
X44114Y-199305D01*
X43677Y-201055D01*
Y-202805D01*
X44114Y-204555D01*
X45206Y-206305D01*
X46516Y-207471D01*
X48044Y-207763D01*
X49572Y-207180D01*
X51101Y-205430D01*
G01X61614Y-205722D02*
X62706Y-206888D01*
X64234Y-207763D01*
X65544D01*
X66854Y-207180D01*
X67727Y-206305D01*
X68164Y-205139D01*
X67946Y-203388D01*
X67072Y-202513D01*
X63142Y-200763D01*
X62269Y-198721D01*
X62706Y-197263D01*
X63579Y-196388D01*
X64889Y-196097D01*
X66199Y-196388D01*
X67509Y-197263D01*
G01X82389Y-196097D02*
Y-207763D01*
G01Y-191430D02*
X81952Y-191138D01*
Y-190555D01*
X82389Y-190263D01*
X82826Y-190555D01*
Y-191138D01*
X82389Y-191430D01*
G01X96832Y-212138D02*
X98361Y-213305D01*
X100107Y-213596D01*
X101635Y-213305D01*
X102946Y-211847D01*
X103819Y-209805D01*
Y-196097D01*
G01Y-198430D02*
X102946Y-197263D01*
X101635Y-196388D01*
X100107Y-196097D01*
X98361Y-196680D01*
X97269Y-197846D01*
X96395Y-199888D01*
X95959Y-201930D01*
X96177Y-203680D01*
X97051Y-205722D01*
X98361Y-207180D01*
X100107Y-207763D01*
X101417Y-207471D01*
X102946Y-206305D01*
X103819Y-205139D01*
G01X113677Y-207763D02*
Y-196097D01*
G01Y-199013D02*
X114551Y-197555D01*
X115861Y-196388D01*
X117607Y-196097D01*
X119135Y-196388D01*
X120446Y-197555D01*
X121101Y-199596D01*
Y-207763D01*
G01X131614Y-199888D02*
X138601D01*
X137946Y-197846D01*
X136854Y-196680D01*
X135326Y-196097D01*
X133797Y-196388D01*
X132487Y-197263D01*
X131614Y-199305D01*
X131177Y-201055D01*
Y-202805D01*
X131614Y-204555D01*
X132706Y-206305D01*
X134016Y-207471D01*
X135544Y-207763D01*
X137072Y-207180D01*
X138601Y-205430D01*
G01X149332Y-207763D02*
Y-196097D01*
G01Y-198430D02*
X150424Y-197263D01*
X151516Y-196388D01*
X153044Y-196097D01*
X154135Y-196388D01*
X155446Y-197263D01*
G01X196089Y-252763D02*
Y-235263D01*
X193469Y-238763D01*
G01Y-252763D02*
X198709D01*
G01X213589Y-235263D02*
X211842Y-235846D01*
X210532Y-237305D01*
X209659Y-239054D01*
X209004Y-241388D01*
X208786Y-244013D01*
X209004Y-246638D01*
X209659Y-248972D01*
X210532Y-250722D01*
X211842Y-252180D01*
X213589Y-252763D01*
X215335Y-252180D01*
X216646Y-250722D01*
X217519Y-248972D01*
X218174Y-246638D01*
X218392Y-244013D01*
X218174Y-241388D01*
X217519Y-239054D01*
X216646Y-237305D01*
X215335Y-235846D01*
X213589Y-235263D01*
G01X227159Y-253346D02*
X235019Y-235263D01*
G01X248589Y-252763D02*
Y-235263D01*
X245969Y-238763D01*
G01Y-252763D02*
X251209D01*
G01X261941Y-245472D02*
X263469Y-243430D01*
X264779Y-242263D01*
X266526Y-241680D01*
X268054Y-242263D01*
X269146Y-243430D01*
X270019Y-245180D01*
X270237Y-247221D01*
X270019Y-248972D01*
X269146Y-250722D01*
X267835Y-252180D01*
X266307Y-252763D01*
X264561Y-252180D01*
X263032Y-250430D01*
X262159Y-247805D01*
X261941Y-244888D01*
X262377Y-241097D01*
X263032Y-239054D01*
X264124Y-237013D01*
X265652Y-235555D01*
X267181Y-235263D01*
X268709Y-235846D01*
X269801Y-237305D01*
G01X279659Y-253346D02*
X287519Y-235263D01*
G01X296941Y-238180D02*
X298251Y-236430D01*
X299779Y-235555D01*
X301526Y-235263D01*
X303709Y-235846D01*
X305237Y-237305D01*
X305674Y-239054D01*
X305456Y-240805D01*
X304582Y-242263D01*
X300216Y-245180D01*
X298251Y-247221D01*
X296941Y-250139D01*
X296504Y-252763D01*
X305674D01*
G01X318589Y-235263D02*
X316842Y-235846D01*
X315532Y-237305D01*
X314659Y-239054D01*
X314004Y-241388D01*
X313786Y-244013D01*
X314004Y-246638D01*
X314659Y-248972D01*
X315532Y-250722D01*
X316842Y-252180D01*
X318589Y-252763D01*
X320335Y-252180D01*
X321646Y-250722D01*
X322519Y-248972D01*
X323174Y-246638D01*
X323392Y-244013D01*
X323174Y-241388D01*
X322519Y-239054D01*
X321646Y-237305D01*
X320335Y-235846D01*
X318589Y-235263D01*
G01X336089Y-252763D02*
Y-235263D01*
X333469Y-238763D01*
G01Y-252763D02*
X338709D01*
G01X349441Y-238180D02*
X350751Y-236430D01*
X352279Y-235555D01*
X354026Y-235263D01*
X356209Y-235846D01*
X357737Y-237305D01*
X358174Y-239054D01*
X357956Y-240805D01*
X357082Y-242263D01*
X352716Y-245180D01*
X350751Y-247221D01*
X349441Y-250139D01*
X349004Y-252763D01*
X358174D01*
G01X243786Y-207763D02*
Y-190263D01*
X248152D01*
X249899Y-191138D01*
X251209Y-192305D01*
X252301Y-194054D01*
X253174Y-196097D01*
X253392Y-199013D01*
X253174Y-201930D01*
X252301Y-203972D01*
X251209Y-205722D01*
X249899Y-206888D01*
X248152Y-207763D01*
X243786D01*
G01X270019D02*
Y-196097D01*
G01Y-198138D02*
X269146Y-196972D01*
X267835Y-196388D01*
X266307Y-196097D01*
X264779Y-196680D01*
X263469Y-197846D01*
X262595Y-199596D01*
X262159Y-201930D01*
X262595Y-204263D01*
X263469Y-206013D01*
X264779Y-207180D01*
X266307Y-207763D01*
X267835Y-207471D01*
X269146Y-206597D01*
X270019Y-205430D01*
G01X283589Y-190263D02*
Y-207763D01*
G01X280532Y-196097D02*
X286646D01*
G01X297814Y-199888D02*
X304801D01*
X304146Y-197846D01*
X303054Y-196680D01*
X301526Y-196097D01*
X299997Y-196388D01*
X298687Y-197263D01*
X297814Y-199305D01*
X297377Y-201055D01*
Y-202805D01*
X297814Y-204555D01*
X298906Y-206305D01*
X300216Y-207471D01*
X301744Y-207763D01*
X303272Y-207180D01*
X304801Y-205430D01*
G54D29*
G01X-771361Y-182763D02*
Y-262763D01*
G01Y-218263D02*
X373639D01*
G01X-771361Y-262763D02*
X373639D01*
G01X-775361Y-166763D02*
G02I-12000J0D01*
G01X-780511D02*
G02I-6850J0D01*
G01X-787361Y-182763D02*
Y-150763D01*
G01X-771361Y-166763D02*
X-803361D01*
G01X-771361Y-182763D02*
X373639D01*
G01X-413861D02*
Y-262763D01*
G01X-276361Y-182763D02*
Y-262763D01*
G01X-161361Y-182763D02*
Y-262763D01*
G01X6139Y-182763D02*
Y-262763D01*
G01X176139Y-182763D02*
Y-262763D01*
G01X373639Y-182763D02*
Y-262763D01*
G01X401639Y-166763D02*
G02I-12000J0D01*
G01X396489D02*
G02I-6850J0D01*
G01X389639Y-182763D02*
Y-150763D01*
G01X405639Y-166763D02*
X373639D01*
M02*
